G04 ================== begin FILE IDENTIFICATION RECORD ==================*
G04 Layout Name:  D:/<user>/Wistron_project/16315-1/gbr/16315-1.brd*
G04 Film Name:    L4GND*
G04 File Format:  Gerber RS274X*
G04 File Origin:  Cadence Allegro 16.5-S056*
G04 Origin Date:  Fri Jun 09 15:31:29 2017*
G04 *
G04 Layer:  VIA CLASS/L4GND*
G04 Layer:  PIN/L4GND*
G04 Layer:  ETCH/L4GND*
G04 Layer:  DRAWING FORMAT/LAYER_PCB_STORY*
G04 Layer:  DRAWING FORMAT/LAYER_L4GND*
G04 *
G04 Offset:    (0.00 0.00)*
G04 Mirror:    No*
G04 Mode:      Negative*
G04 Rotation:  0*
G04 FullContactRelief:  No*
G04 UndefLineWidth:     6.00*
G04 ================== end FILE IDENTIFICATION RECORD ====================*
%FSLAX35Y35*MOIN*%
%IR0*IPPOS*OFA0.00000B0.00000*MIA0B0*SFA1.00000B1.00000*%
%ADD24C,.03*%
%ADD44C,.04*%
%ADD14C,.032*%
%ADD42C,.052*%
%ADD33C,.043*%
%ADD22C,.036*%
%ADD20C,.081*%
%ADD32C,.047*%
%ADD19C,.065*%
%ADD38C,.057*%
%ADD43C,.058*%
%AMMACRO31*
4,1,15,.00398,.00044,
.003999,.000208,
.004004,-.000025,
.003996,-.000258,
.00398,-.00044,
.00483,-.00129,
.004897,-.001007,
.004947,-.000721,
.004981,-.000432,
.004997,-.000141,
.004997,.000149,
.00498,.00044,
.004946,.000729,
.004895,.001015,
.00483,.00129,
.00398,.00044,
90.*
4,1,15,.00044,-.00398,
.000208,-.003999,
-.000025,-.004004,
-.000258,-.003996,
-.00044,-.00398,
-.00129,-.00483,
-.001007,-.004897,
-.000721,-.004947,
-.000432,-.004981,
-.000141,-.004997,
.000149,-.004997,
.00044,-.00498,
.000729,-.004946,
.001015,-.004895,
.00129,-.00483,
.00044,-.00398,
90.*
4,1,15,-.00398,-.00044,
-.003999,-.000208,
-.004004,.000025,
-.003996,.000258,
-.00398,.00044,
-.00483,.00129,
-.004897,.001007,
-.004947,.000721,
-.004981,.000432,
-.004997,.000141,
-.004997,-.000149,
-.00498,-.00044,
-.004946,-.000729,
-.004895,-.001015,
-.00483,-.00129,
-.00398,-.00044,
90.*
4,1,15,-.00044,.00398,
-.000208,.003999,
.000025,.004004,
.000258,.003996,
.00044,.00398,
.00129,.00483,
.001007,.004897,
.000721,.004947,
.000432,.004981,
.000141,.004997,
-.000149,.004997,
-.00044,.00498,
-.000729,.004946,
-.001015,.004895,
-.00129,.00483,
-.00044,.00398,
90.*
%
%ADD31MACRO31*%
%AMMACRO28*
4,1,15,-.00398,.00044,
-.003999,.000208,
-.004004,-.000025,
-.003996,-.000258,
-.00398,-.00044,
-.00483,-.00129,
-.004897,-.001007,
-.004947,-.000721,
-.004981,-.000432,
-.004997,-.000141,
-.004997,.000149,
-.00498,.00044,
-.004946,.000729,
-.004895,.001015,
-.00483,.00129,
-.00398,.00044,
90.*
4,1,15,-.00044,-.00398,
-.000208,-.003999,
.000025,-.004004,
.000258,-.003996,
.00044,-.00398,
.00129,-.00483,
.001007,-.004897,
.000721,-.004947,
.000432,-.004981,
.000141,-.004997,
-.000149,-.004997,
-.00044,-.00498,
-.000729,-.004946,
-.001015,-.004895,
-.00129,-.00483,
-.00044,-.00398,
90.*
4,1,15,.00398,-.00044,
.003999,-.000208,
.004004,.000025,
.003996,.000258,
.00398,.00044,
.00483,.00129,
.004897,.001007,
.004947,.000721,
.004981,.000432,
.004997,.000141,
.004997,-.000149,
.00498,-.00044,
.004946,-.000729,
.004895,-.001015,
.00483,-.00129,
.00398,-.00044,
90.*
4,1,15,.00044,.00398,
.000208,.003999,
-.000025,.004004,
-.000258,.003996,
-.00044,.00398,
-.00129,.00483,
-.001007,.004897,
-.000721,.004947,
-.000432,.004981,
-.000141,.004997,
.000149,.004997,
.00044,.00498,
.000729,.004946,
.001015,.004895,
.00129,.00483,
.00044,.00398,
90.*
%
%ADD28MACRO28*%
%AMMACRO11*
4,1,15,.00398,.00044,
.003999,.000208,
.004004,-.000025,
.003996,-.000258,
.00398,-.00044,
.00483,-.00129,
.004897,-.001007,
.004947,-.000721,
.004981,-.000432,
.004997,-.000141,
.004997,.000149,
.00498,.00044,
.004946,.000729,
.004895,.001015,
.00483,.00129,
.00398,.00044,
0.0*
4,1,15,.00044,-.00398,
.000208,-.003999,
-.000025,-.004004,
-.000258,-.003996,
-.00044,-.00398,
-.00129,-.00483,
-.001007,-.004897,
-.000721,-.004947,
-.000432,-.004981,
-.000141,-.004997,
.000149,-.004997,
.00044,-.00498,
.000729,-.004946,
.001015,-.004895,
.00129,-.00483,
.00044,-.00398,
0.0*
4,1,15,-.00398,-.00044,
-.003999,-.000208,
-.004004,.000025,
-.003996,.000258,
-.00398,.00044,
-.00483,.00129,
-.004897,.001007,
-.004947,.000721,
-.004981,.000432,
-.004997,.000141,
-.004997,-.000149,
-.00498,-.00044,
-.004946,-.000729,
-.004895,-.001015,
-.00483,-.00129,
-.00398,-.00044,
0.0*
4,1,15,-.00044,.00398,
-.000208,.003999,
.000025,.004004,
.000258,.003996,
.00044,.00398,
.00129,.00483,
.001007,.004897,
.000721,.004947,
.000432,.004981,
.000141,.004997,
-.000149,.004997,
-.00044,.00498,
-.000729,.004946,
-.001015,.004895,
-.00129,.00483,
-.00044,.00398,
0.0*
%
%ADD11MACRO11*%
%AMMACRO37*
4,1,47,.19499,.0719,
.215281,.036007,
.229031,-.002865,
.235822,-.043533,
.235448,-.084763,
.22792,-.125302,
.213467,-.163917,
.192528,-.199436,
.16574,-.23078,
.133915,-.256995,
.098022,-.277286,
.059151,-.291036,
.018482,-.297827,
-.022748,-.297453,
-.063286,-.289925,
-.101902,-.275472,
-.137421,-.254533,
-.168764,-.227745,
-.19498,-.19592,
-.215271,-.160027,
-.229021,-.121156,
-.235812,-.080487,
-.235438,-.039257,
-.22791,.001281,
-.213457,.039897,
-.19498,.0719,
-.17079,.109417,
-.148822,.148276,
-.129151,.188348,
-.11538,.22052,
-.105587,.239854,
-.092586,.257193,
-.076771,.272012,
-.058623,.283859,
-.038693,.292375,
-.017588,.297301,
.004052,.298487,
.025569,.295897,
.04631,.28961,
.065644,.279817,
.082983,.266816,
.097802,.251001,
.109649,.232853,
.1154,.22052,
.133222,.179593,
.153393,.139771,
.175846,.101189,
.19499,.0719,
0.0*
%
%ADD37MACRO37*%
%AMMACRO23*
4,1,15,-.00398,.00044,
-.003999,.000208,
-.004004,-.000025,
-.003996,-.000258,
-.00398,-.00044,
-.00483,-.00129,
-.004897,-.001007,
-.004947,-.000721,
-.004981,-.000432,
-.004997,-.000141,
-.004997,.000149,
-.00498,.00044,
-.004946,.000729,
-.004895,.001015,
-.00483,.00129,
-.00398,.00044,
0.0*
4,1,15,-.00044,-.00398,
-.000208,-.003999,
.000025,-.004004,
.000258,-.003996,
.00044,-.00398,
.00129,-.00483,
.001007,-.004897,
.000721,-.004947,
.000432,-.004981,
.000141,-.004997,
-.000149,-.004997,
-.00044,-.00498,
-.000729,-.004946,
-.001015,-.004895,
-.00129,-.00483,
-.00044,-.00398,
0.0*
4,1,15,.00398,-.00044,
.003999,-.000208,
.004004,.000025,
.003996,.000258,
.00398,.00044,
.00483,.00129,
.004897,.001007,
.004947,.000721,
.004981,.000432,
.004997,.000141,
.004997,-.000149,
.00498,-.00044,
.004946,-.000729,
.004895,-.001015,
.00483,-.00129,
.00398,-.00044,
0.0*
4,1,15,.00044,.00398,
.000208,.003999,
-.000025,.004004,
-.000258,.003996,
-.00044,.00398,
-.00129,.00483,
-.001007,.004897,
-.000721,.004947,
-.000432,.004981,
-.000141,.004997,
.000149,.004997,
.00044,.00498,
.000729,.004946,
.001015,.004895,
.00129,.00483,
.00044,.00398,
0.0*
%
%ADD23MACRO23*%
%ADD39C,.121*%
%ADD34C,.122*%
%ADD15C,.114*%
%ADD18C,.115*%
%ADD12O,.206X.285*%
%ADD35C,.125*%
%ADD10C,.206*%
%ADD36C,.432*%
%ADD26C,.18*%
%ADD13C,.208*%
%ADD40O,.159X.237*%
%ADD27C,.139*%
%ADD17C,.265*%
%ADD41C,.159*%
%ADD45C,.178*%
%AMMACRO25*
4,1,15,.00398,.00044,
.003999,.000208,
.004004,-.000025,
.003996,-.000258,
.00398,-.00044,
.00483,-.00129,
.004897,-.001007,
.004947,-.000721,
.004981,-.000432,
.004997,-.000141,
.004997,.000149,
.00498,.00044,
.004946,.000729,
.004895,.001015,
.00483,.00129,
.00398,.00044,
270.*
4,1,15,.00044,-.00398,
.000208,-.003999,
-.000025,-.004004,
-.000258,-.003996,
-.00044,-.00398,
-.00129,-.00483,
-.001007,-.004897,
-.000721,-.004947,
-.000432,-.004981,
-.000141,-.004997,
.000149,-.004997,
.00044,-.00498,
.000729,-.004946,
.001015,-.004895,
.00129,-.00483,
.00044,-.00398,
270.*
4,1,15,-.00398,-.00044,
-.003999,-.000208,
-.004004,.000025,
-.003996,.000258,
-.00398,.00044,
-.00483,.00129,
-.004897,.001007,
-.004947,.000721,
-.004981,.000432,
-.004997,.000141,
-.004997,-.000149,
-.00498,-.00044,
-.004946,-.000729,
-.004895,-.001015,
-.00483,-.00129,
-.00398,-.00044,
270.*
4,1,15,-.00044,.00398,
-.000208,.003999,
.000025,.004004,
.000258,.003996,
.00044,.00398,
.00129,.00483,
.001007,.004897,
.000721,.004947,
.000432,.004981,
.000141,.004997,
-.000149,.004997,
-.00044,.00498,
-.000729,.004946,
-.001015,.004895,
-.00129,.00483,
-.00044,.00398,
270.*
%
%ADD25MACRO25*%
%AMMACRO16*
4,1,15,.00398,.00044,
.003999,.000208,
.004004,-.000025,
.003996,-.000258,
.00398,-.00044,
.00483,-.00129,
.004897,-.001007,
.004947,-.000721,
.004981,-.000432,
.004997,-.000141,
.004997,.000149,
.00498,.00044,
.004946,.000729,
.004895,.001015,
.00483,.00129,
.00398,.00044,
180.*
4,1,15,.00044,-.00398,
.000208,-.003999,
-.000025,-.004004,
-.000258,-.003996,
-.00044,-.00398,
-.00129,-.00483,
-.001007,-.004897,
-.000721,-.004947,
-.000432,-.004981,
-.000141,-.004997,
.000149,-.004997,
.00044,-.00498,
.000729,-.004946,
.001015,-.004895,
.00129,-.00483,
.00044,-.00398,
180.*
4,1,15,-.00398,-.00044,
-.003999,-.000208,
-.004004,.000025,
-.003996,.000258,
-.00398,.00044,
-.00483,.00129,
-.004897,.001007,
-.004947,.000721,
-.004981,.000432,
-.004997,.000141,
-.004997,-.000149,
-.00498,-.00044,
-.004946,-.000729,
-.004895,-.001015,
-.00483,-.00129,
-.00398,-.00044,
180.*
4,1,15,-.00044,.00398,
-.000208,.003999,
.000025,.004004,
.000258,.003996,
.00044,.00398,
.00129,.00483,
.001007,.004897,
.000721,.004947,
.000432,.004981,
.000141,.004997,
-.000149,.004997,
-.00044,.00498,
-.000729,.004946,
-.001015,.004895,
-.00129,.00483,
-.00044,.00398,
180.*
%
%ADD16MACRO16*%
%AMMACRO30*
4,1,15,-.00398,.00044,
-.003999,.000208,
-.004004,-.000025,
-.003996,-.000258,
-.00398,-.00044,
-.00483,-.00129,
-.004897,-.001007,
-.004947,-.000721,
-.004981,-.000432,
-.004997,-.000141,
-.004997,.000149,
-.00498,.00044,
-.004946,.000729,
-.004895,.001015,
-.00483,.00129,
-.00398,.00044,
270.*
4,1,15,-.00044,-.00398,
-.000208,-.003999,
.000025,-.004004,
.000258,-.003996,
.00044,-.00398,
.00129,-.00483,
.001007,-.004897,
.000721,-.004947,
.000432,-.004981,
.000141,-.004997,
-.000149,-.004997,
-.00044,-.00498,
-.000729,-.004946,
-.001015,-.004895,
-.00129,-.00483,
-.00044,-.00398,
270.*
4,1,15,.00398,-.00044,
.003999,-.000208,
.004004,.000025,
.003996,.000258,
.00398,.00044,
.00483,.00129,
.004897,.001007,
.004947,.000721,
.004981,.000432,
.004997,.000141,
.004997,-.000149,
.00498,-.00044,
.004946,-.000729,
.004895,-.001015,
.00483,-.00129,
.00398,-.00044,
270.*
4,1,15,.00044,.00398,
.000208,.003999,
-.000025,.004004,
-.000258,.003996,
-.00044,.00398,
-.00129,.00483,
-.001007,.004897,
-.000721,.004947,
-.000432,.004981,
-.000141,.004997,
.000149,.004997,
.00044,.00498,
.000729,.004946,
.001015,.004895,
.00129,.00483,
.00044,.00398,
270.*
%
%ADD30MACRO30*%
%AMMACRO29*
4,1,15,-.00398,.00044,
-.003999,.000208,
-.004004,-.000025,
-.003996,-.000258,
-.00398,-.00044,
-.00483,-.00129,
-.004897,-.001007,
-.004947,-.000721,
-.004981,-.000432,
-.004997,-.000141,
-.004997,.000149,
-.00498,.00044,
-.004946,.000729,
-.004895,.001015,
-.00483,.00129,
-.00398,.00044,
180.*
4,1,15,-.00044,-.00398,
-.000208,-.003999,
.000025,-.004004,
.000258,-.003996,
.00044,-.00398,
.00129,-.00483,
.001007,-.004897,
.000721,-.004947,
.000432,-.004981,
.000141,-.004997,
-.000149,-.004997,
-.00044,-.00498,
-.000729,-.004946,
-.001015,-.004895,
-.00129,-.00483,
-.00044,-.00398,
180.*
4,1,15,.00398,-.00044,
.003999,-.000208,
.004004,.000025,
.003996,.000258,
.00398,.00044,
.00483,.00129,
.004897,.001007,
.004947,.000721,
.004981,.000432,
.004997,.000141,
.004997,-.000149,
.00498,-.00044,
.004946,-.000729,
.004895,-.001015,
.00483,-.00129,
.00398,-.00044,
180.*
4,1,15,.00044,.00398,
.000208,.003999,
-.000025,.004004,
-.000258,.003996,
-.00044,.00398,
-.00129,.00483,
-.001007,.004897,
-.000721,.004947,
-.000432,.004981,
-.000141,.004997,
.000149,.004997,
.00044,.00498,
.000729,.004946,
.001015,.004895,
.00129,.00483,
.00044,.00398,
180.*
%
%ADD29MACRO29*%
%ADD46C,.02*%
%ADD47C,.006*%
%ADD57C,.06104*%
%ADD58C,.07704*%
%ADD59C,.11004*%
%ADD56C,.11104*%
%ADD63C,.11704*%
%ADD60C,.13504*%
%ADD62C,.11804*%
%ADD55C,.37504*%
%ADD65C,.29531*%
%ADD54C,.29532*%
%ADD64C,.29533*%
%ADD61C,.23629*%
%ADD48O,.55202X.78802*%
%ADD51O,.09834X.04322*%
%ADD49O,.55204X.78804*%
%ADD53O,.09854X.04342*%
%ADD50O,.09836X.04324*%
%ADD52O,.09856X.04344*%
G75*
%LPD*%
G75*
G36*
G01X-6000Y-158756D02*
X1940843D01*
Y1664268D01*
X-6000D01*
Y-158756D01*
G37*
%LPC*%
G75*
G36*
G01X1216535Y1655264D02*
G02X1217468Y1654331I0J-933D01*
G01Y1476378D01*
G02X1216535Y1475445I-933J0D01*
G01X1168110D01*
G03X1161169Y1468504I0J-6941D01*
G01Y1378740D01*
G03X1168110Y1371799I6941J0D01*
G01X1930906D01*
G02X1931839Y1370866I0J-933D01*
G01Y3937D01*
G02X1930906Y3004I-933J0D01*
G01X1562992D01*
G02X1562059Y3937I0J933D01*
G01Y55118D01*
G03X1555118Y62059I-6941J0D01*
G01X1374016D01*
G03X1367075Y55118I0J-6941D01*
G01Y3937D01*
G02X1366142Y3004I-933J0D01*
G01X1185039D01*
G03X1178098Y-3937I0J-6941D01*
G01Y-148819D01*
G02X1177165Y-149752I-933J0D01*
G01X870079D01*
G02X869146Y-148819I0J933D01*
G01Y-11811D01*
G03X862205Y-4870I-6941J0D01*
G01X791339D01*
G02X790406Y-3937I0J933D01*
G03X783465Y3004I-6941J0D01*
G01X594488D01*
G02X593555Y3937I0J933D01*
G01Y55118D01*
G03X586614Y62059I-6941J0D01*
G01X405512D01*
G03X398571Y55118I0J-6941D01*
G01Y3937D01*
G02X397638Y3004I-933J0D01*
G01X3937D01*
G02X3004Y3937I0J933D01*
G01Y12071D01*
G02X3714Y12323I400J0D01*
G03X29922Y21653I11443J9331D01*
G01Y21654D01*
G03X3714Y30984I-14765J0D01*
G02X3004Y31236I-310J253D01*
G01Y464768D01*
G02X3713Y465022I400J0D01*
G03X12310Y459884I11444J9387D01*
G03X18004I2847J10575D01*
G03Y488934I-2847J14525D01*
G03X12310I-2847J-10575D01*
G03X3713Y483796I2847J-14525D01*
G02X3004Y484050I-309J254D01*
G01Y1370866D01*
G02X3937Y1371799I933J0D01*
G01X746850D01*
G03X753791Y1378740I0J6941D01*
G01Y1464567D01*
G02X754724Y1465500I933J0D01*
G01X783465D01*
G03X790406Y1472441I0J6941D01*
G01Y1654331D01*
G02X791339Y1655264I933J0D01*
G01X1216535D01*
G37*
%LPD*%
G75*
G36*
G01X1124313Y534842D02*
X1124318Y534833D01*
X1116440Y530894D01*
X1116437Y530899D01*
X1116339Y530857D01*
G02X1113786Y535977I-1183J2607D01*
G01X1113872Y536027D01*
X1113870Y536032D01*
X1121747Y539971D01*
X1121753Y539965D01*
X1121814Y539992D01*
G02X1124313Y534842I1217J-2591D01*
G37*
G36*
G01X956203D02*
X956208Y534833D01*
X948330Y530894D01*
X948327Y530899D01*
X948229Y530857D01*
G02X945676Y535977I-1183J2607D01*
G01X945762Y536027D01*
X945760Y536032D01*
X953637Y539971D01*
X953643Y539965D01*
X953704Y539992D01*
G02X956203Y534842I1217J-2591D01*
G37*
G36*
G01X1897508Y459879D02*
G02X1891860I-2824J10580D01*
G02Y488939I2824J14530D01*
G02X1897508I2824J-10580D01*
G02Y459879I-2824J-14530D01*
G37*
G36*
G01X956203Y424606D02*
X956208Y424597D01*
X948330Y420658D01*
X948327Y420663D01*
X948229Y420621D01*
G02X945676Y425741I-1183J2607D01*
G01X945762Y425791D01*
X945760Y425796D01*
X953637Y429735D01*
X953643Y429729D01*
X953704Y429756D01*
G02X956203Y424606I1217J-2591D01*
G37*
G36*
G01X907745Y-40121D02*
G02X902097I-2824J10580D01*
G02Y-11061I2824J14530D01*
G02X907745I2824J-10580D01*
G02Y-40121I-2824J-14530D01*
G37*
G36*
G01X1535036Y77756D02*
Y72244D01*
G02X1530712Y72245I-2162J1D01*
G01Y77756D01*
G02X1535036I2162J0D01*
G37*
G36*
G01Y91930D02*
Y86417D01*
G02X1530712Y86418I-2162J1D01*
G01Y91930D01*
G02X1535036I2162J0D01*
G37*
G36*
G01X1527948Y87993D02*
Y82480D01*
G02X1523626Y82481I-2161J1D01*
G01Y87993D01*
G02X1527948I2161J0D01*
G37*
G36*
G01X1535036Y120276D02*
Y114763D01*
G02X1530712Y114764I-2162J1D01*
G01Y120276D01*
G02X1535036I2162J0D01*
G37*
G36*
G01X1527948Y73819D02*
Y68306D01*
G02X1523626Y68307I-2161J1D01*
G01Y73819D01*
G02X1527948I2161J0D01*
G37*
G36*
G01X1520862Y77756D02*
Y72244D01*
G02X1516540Y72245I-2161J1D01*
G01Y77756D01*
G02X1520862I2161J0D01*
G37*
G36*
G01X1506690D02*
Y72244D01*
G02X1502366Y72245I-2162J1D01*
G01Y77756D01*
G02X1506690I2162J0D01*
G37*
G36*
G01X1492516D02*
Y72244D01*
G02X1488192Y72245I-2162J1D01*
G01Y77756D01*
G02X1492516I2162J0D01*
G37*
G36*
G01X1520862Y91930D02*
Y86417D01*
G02X1516540Y86418I-2161J1D01*
G01Y91930D01*
G02X1520862I2161J0D01*
G37*
G36*
G01X1513776Y87993D02*
Y82480D01*
G02X1509452Y82481I-2162J1D01*
G01Y87993D01*
G02X1513776I2162J0D01*
G37*
G36*
G01X1506690Y91930D02*
Y86417D01*
G02X1502366Y86418I-2162J1D01*
G01Y91930D01*
G02X1506690I2162J0D01*
G37*
G36*
G01X1499602Y87993D02*
Y82480D01*
G02X1495280Y82481I-2161J1D01*
G01Y87993D01*
G02X1499602I2161J0D01*
G37*
G36*
G01X1492516Y91930D02*
Y86417D01*
G02X1488192Y86418I-2162J1D01*
G01Y91930D01*
G02X1492516I2162J0D01*
G37*
G36*
G01X1485430Y87993D02*
Y82480D01*
G02X1481106Y82481I-2162J1D01*
G01Y87993D01*
G02X1485430I2162J0D01*
G37*
G36*
G01X1506700Y120276D02*
Y114763D01*
G02X1502356Y114764I-2172J1D01*
G01Y120276D01*
G02X1506700I2172J0D01*
G37*
G36*
G01X1513776Y73819D02*
Y68306D01*
G02X1509452Y68307I-2162J1D01*
G01Y73819D01*
G02X1513776I2162J0D01*
G37*
G36*
G01X1499602D02*
Y68306D01*
G02X1495280Y68307I-2161J1D01*
G01Y73819D01*
G02X1499602I2161J0D01*
G37*
G36*
G01X1485430D02*
Y68306D01*
G02X1481106Y68307I-2162J1D01*
G01Y73819D01*
G02X1485430I2162J0D01*
G37*
G36*
G01X1449996Y77756D02*
Y72244D01*
G02X1445674Y72245I-2161J1D01*
G01Y77756D01*
G02X1449996I2161J0D01*
G37*
G36*
G01X1435822D02*
Y72244D01*
G02X1431500Y72245I-2161J1D01*
G01Y77756D01*
G02X1435822I2161J0D01*
G37*
G36*
G01X1449996Y91930D02*
Y86417D01*
G02X1445674Y86418I-2161J1D01*
G01Y91930D01*
G02X1449996I2161J0D01*
G37*
G36*
G01X1442910Y87993D02*
Y82480D01*
G02X1438586Y82481I-2162J1D01*
G01Y87993D01*
G02X1442910I2162J0D01*
G37*
G36*
G01X1435822Y91930D02*
Y86417D01*
G02X1431500Y86418I-2161J1D01*
G01Y91930D01*
G02X1435822I2161J0D01*
G37*
G36*
G01X1445664Y114764D02*
Y120277D01*
G02X1450006Y120276I2171J-1D01*
G01Y114764D01*
G02X1445664I-2171J0D01*
G37*
G36*
G01X1442910Y73819D02*
Y68306D01*
G02X1438586Y68307I-2162J1D01*
G01Y73819D01*
G02X1442910I2162J0D01*
G37*
G36*
G01X1404234Y190242D02*
Y185741D01*
G02X1401192Y185742I-1521J1D01*
G01Y190242D01*
G02X1404234I1521J0D01*
G37*
G36*
G01X1385463Y166302D02*
X1380962D01*
G02X1380963Y169344I1J1521D01*
G01X1385463D01*
G02Y166302I0J-1521D01*
G37*
G36*
G01X1421650Y77756D02*
Y72244D01*
G02X1417326Y72245I-2162J1D01*
G01Y77756D01*
G02X1421650I2162J0D01*
G37*
G36*
G01X1407476D02*
Y72244D01*
G02X1403154Y72245I-2161J1D01*
G01Y77756D01*
G02X1407476I2161J0D01*
G37*
G36*
G01X1428736Y87993D02*
Y82480D01*
G02X1424414Y82481I-2161J1D01*
G01Y87993D01*
G02X1428736I2161J0D01*
G37*
G36*
G01X1421650Y91930D02*
Y86417D01*
G02X1417326Y86418I-2162J1D01*
G01Y91930D01*
G02X1421650I2162J0D01*
G37*
G36*
G01X1414564Y87993D02*
Y82480D01*
G02X1410240Y82481I-2162J1D01*
G01Y87993D01*
G02X1414564I2162J0D01*
G37*
G36*
G01X1407476Y91930D02*
Y86417D01*
G02X1403154Y86418I-2161J1D01*
G01Y91930D01*
G02X1407476I2161J0D01*
G37*
G36*
G01X1400390Y87993D02*
Y82480D01*
G02X1396066Y82481I-2162J1D01*
G01Y87993D01*
G02X1400390I2162J0D01*
G37*
G36*
G01X1428736Y116339D02*
Y110826D01*
G02X1424414Y110827I-2161J1D01*
G01Y116339D01*
G02X1428736I2161J0D01*
G37*
G36*
G01Y73819D02*
Y68306D01*
G02X1424414Y68307I-2161J1D01*
G01Y73819D01*
G02X1428736I2161J0D01*
G37*
G36*
G01X1414564D02*
Y68306D01*
G02X1410240Y68307I-2162J1D01*
G01Y73819D01*
G02X1414564I2162J0D01*
G37*
G36*
G01X1400390D02*
Y68306D01*
G02X1396066Y68307I-2162J1D01*
G01Y73819D01*
G02X1400390I2162J0D01*
G37*
G36*
G01X1261462Y1080754D02*
Y1076253D01*
G02X1258138Y1076254I-1662J1D01*
G01Y1080754D01*
G02X1261462I1662J0D01*
G37*
G36*
G01X1113922Y709162D02*
X1121763Y713082D01*
X1121764Y713083D01*
G02X1124266Y708159I1267J-2454D01*
G01X1116392Y704222D01*
G02X1113922Y709162I-1235J2470D01*
G37*
G36*
G01X1104199Y696183D02*
X1104034Y696253D01*
X1104032Y696249D01*
X1096156Y700187D01*
Y700195D01*
X1096053Y700252D01*
G02X1098557Y705390I1388J2503D01*
G01X1098722Y705320D01*
X1098724Y705324D01*
X1106601Y701386D01*
X1106599Y701382D01*
X1106767Y701283D01*
G02X1104199Y696183I-1453J-2465D01*
G37*
G36*
G01X1113922Y693414D02*
X1121763Y697334D01*
X1121764Y697335D01*
G02X1124266Y692411I1267J-2454D01*
G01X1116392Y688474D01*
G02X1113922Y693414I-1235J2470D01*
G37*
G36*
G01Y677666D02*
X1121763Y681586D01*
X1121764Y681587D01*
G02X1124266Y676663I1267J-2454D01*
G01X1116392Y672726D01*
G02X1113922Y677666I-1235J2470D01*
G37*
G36*
G01Y661918D02*
X1121763Y665838D01*
X1121764Y665839D01*
G02X1124266Y660915I1267J-2454D01*
G01X1116392Y656978D01*
G02X1113922Y661918I-1235J2470D01*
G37*
G36*
G01X1104199Y680435D02*
X1104034Y680505D01*
X1104032Y680501D01*
X1096156Y684439D01*
Y684447D01*
X1096053Y684504D01*
G02X1098557Y689642I1388J2503D01*
G01X1098722Y689572D01*
X1098724Y689576D01*
X1106601Y685638D01*
X1106599Y685634D01*
X1106767Y685535D01*
G02X1104199Y680435I-1453J-2465D01*
G37*
G36*
G01Y664687D02*
X1104034Y664757D01*
X1104032Y664753D01*
X1096156Y668691D01*
Y668699D01*
X1096053Y668756D01*
G02X1098557Y673894I1388J2503D01*
G01X1098722Y673824D01*
X1098724Y673828D01*
X1106601Y669890D01*
X1106599Y669886D01*
X1106767Y669787D01*
G02X1104199Y664687I-1453J-2465D01*
G37*
G36*
G01Y648939D02*
X1104034Y649009D01*
X1104032Y649005D01*
X1096156Y652943D01*
Y652951D01*
X1096053Y653008D01*
G02X1098557Y658146I1388J2503D01*
G01X1098722Y658076D01*
X1098724Y658080D01*
X1106601Y654142D01*
X1106599Y654138D01*
X1106767Y654039D01*
G02X1104199Y648939I-1453J-2465D01*
G37*
G36*
G01X1113922Y646170D02*
X1121763Y650090D01*
X1121764Y650091D01*
G02X1124266Y645167I1267J-2454D01*
G01X1116392Y641230D01*
G02X1113922Y646170I-1235J2470D01*
G37*
G36*
G01X1124266Y629419D02*
X1116425Y625499D01*
X1116424Y625498D01*
G02X1113922Y630422I-1267J2454D01*
G01X1121796Y634359D01*
G02X1124266Y629419I1235J-2470D01*
G37*
G36*
G01X1113922Y614674D02*
X1121763Y618594D01*
X1121764Y618595D01*
G02X1124266Y613671I1267J-2454D01*
G01X1116392Y609734D01*
G02X1113922Y614674I-1235J2470D01*
G37*
G36*
G01X1104039Y601780D02*
X1096133Y605733D01*
X1096062Y605771D01*
G02X1098717Y610817I1379J2496D01*
G01X1106591Y606880D01*
G02X1104039Y601780I-1276J-2550D01*
G37*
G36*
G01Y617528D02*
X1096133Y621481D01*
X1096062Y621519D01*
G02X1098717Y626565I1379J2496D01*
G01X1106591Y622628D01*
G02X1104039Y617528I-1276J-2550D01*
G37*
G36*
G01Y633276D02*
X1096133Y637229D01*
X1096062Y637267D01*
G02X1098717Y642313I1379J2496D01*
G01X1106591Y638376D01*
G02X1104039Y633276I-1276J-2550D01*
G37*
G36*
G01X1113922Y598926D02*
X1121763Y602846D01*
X1121764Y602847D01*
G02X1124266Y597923I1267J-2454D01*
G01X1116392Y593986D01*
G02X1113922Y598926I-1235J2470D01*
G37*
G36*
G01X1104039Y586032D02*
X1096133Y589985D01*
X1096062Y590023D01*
G02X1098717Y595069I1379J2496D01*
G01X1106591Y591132D01*
G02X1104039Y586032I-1276J-2550D01*
G37*
G36*
G01Y507292D02*
X1096133Y511245D01*
X1096062Y511283D01*
G02X1098717Y516329I1379J2496D01*
G01X1106591Y512392D01*
G02X1104039Y507292I-1276J-2550D01*
G37*
G36*
G01X1104199Y538703D02*
X1104034Y538773D01*
X1104032Y538769D01*
X1096156Y542707D01*
Y542715D01*
X1096053Y542772D01*
G02X1098557Y547910I1388J2503D01*
G01X1098722Y547840D01*
X1098724Y547844D01*
X1106601Y543906D01*
X1106599Y543902D01*
X1106767Y543803D01*
G02X1104199Y538703I-1453J-2465D01*
G37*
G36*
G01X1113922Y504438D02*
X1121763Y508358D01*
X1121764Y508359D01*
G02X1124266Y503435I1267J-2454D01*
G01X1116392Y499498D01*
G02X1113922Y504438I-1235J2470D01*
G37*
G36*
G01Y488690D02*
X1121763Y492610D01*
X1121764Y492611D01*
G02X1124266Y487687I1267J-2454D01*
G01X1116392Y483750D01*
G02X1113922Y488690I-1235J2470D01*
G37*
G36*
G01Y472942D02*
X1121763Y476862D01*
X1121764Y476863D01*
G02X1124266Y471939I1267J-2454D01*
G01X1116392Y468002D01*
G02X1113922Y472942I-1235J2470D01*
G37*
G36*
G01X1104039Y460048D02*
X1096133Y464001D01*
X1096062Y464039D01*
G02X1098717Y469085I1379J2496D01*
G01X1106591Y465148D01*
G02X1104039Y460048I-1276J-2550D01*
G37*
G36*
G01Y475796D02*
X1096133Y479749D01*
X1096062Y479787D01*
G02X1098717Y484833I1379J2496D01*
G01X1106591Y480896D01*
G02X1104039Y475796I-1276J-2550D01*
G37*
G36*
G01Y491544D02*
X1096133Y495497D01*
X1096062Y495535D01*
G02X1098717Y500581I1379J2496D01*
G01X1106591Y496644D01*
G02X1104039Y491544I-1276J-2550D01*
G37*
G36*
G01X1098676Y453257D02*
X1106550Y449320D01*
G02X1104080Y444380I-1235J-2470D01*
G01X1096239Y448301D01*
X1096238D01*
G02X1098676Y453257I1203J2486D01*
G37*
G36*
G01X1113922Y457194D02*
X1121763Y461114D01*
X1121764Y461115D01*
G02X1124266Y456191I1267J-2454D01*
G01X1116392Y452254D01*
G02X1113922Y457194I-1235J2470D01*
G37*
G36*
G01X1113872Y425796D02*
X1121746Y429733D01*
G02X1124316Y424597I1285J-2568D01*
G01X1116442Y420660D01*
G02X1113872Y425796I-1285J2568D01*
G37*
G36*
G01X1113922Y330029D02*
X1121763Y333949D01*
X1121764Y333950D01*
G02X1124266Y329026I1267J-2454D01*
G01X1116392Y325089D01*
G02X1113922Y330029I-1235J2470D01*
G37*
G36*
G01X1104199Y317050D02*
X1104034Y317120D01*
X1104032Y317116D01*
X1096156Y321054D01*
Y321062D01*
X1096053Y321119D01*
G02X1098557Y326257I1388J2503D01*
G01X1098722Y326187D01*
X1098724Y326191D01*
X1106601Y322253D01*
X1106599Y322249D01*
X1106767Y322150D01*
G02X1104199Y317050I-1453J-2465D01*
G37*
G36*
G01X1113922Y314281D02*
X1121763Y318201D01*
X1121764Y318202D01*
G02X1124266Y313278I1267J-2454D01*
G01X1116392Y309341D01*
G02X1113922Y314281I-1235J2470D01*
G37*
G36*
G01X1104199Y269806D02*
X1104034Y269876D01*
X1104032Y269872D01*
X1096156Y273810D01*
Y273818D01*
X1096053Y273875D01*
G02X1098557Y279013I1388J2503D01*
G01X1098722Y278943D01*
X1098724Y278947D01*
X1106601Y275009D01*
X1106599Y275005D01*
X1106767Y274906D01*
G02X1104199Y269806I-1453J-2465D01*
G37*
G36*
G01X1113922Y282785D02*
X1121763Y286705D01*
X1121764Y286706D01*
G02X1124266Y281782I1267J-2454D01*
G01X1116392Y277845D01*
G02X1113922Y282785I-1235J2470D01*
G37*
G36*
G01Y267037D02*
X1121763Y270957D01*
X1121764Y270958D01*
G02X1124266Y266034I1267J-2454D01*
G01X1116392Y262097D01*
G02X1113922Y267037I-1235J2470D01*
G37*
G36*
G01Y298533D02*
X1121763Y302453D01*
X1121764Y302454D01*
G02X1124266Y297530I1267J-2454D01*
G01X1116392Y293593D01*
G02X1113922Y298533I-1235J2470D01*
G37*
G36*
G01X1104199Y301302D02*
X1104034Y301372D01*
X1104032Y301368D01*
X1096156Y305306D01*
Y305314D01*
X1096053Y305371D01*
G02X1098557Y310509I1388J2503D01*
G01X1098722Y310439D01*
X1098724Y310443D01*
X1106601Y306505D01*
X1106599Y306501D01*
X1106767Y306402D01*
G02X1104199Y301302I-1453J-2465D01*
G37*
G36*
G01Y285554D02*
X1104034Y285624D01*
X1104032Y285620D01*
X1096156Y289558D01*
Y289566D01*
X1096053Y289623D01*
G02X1098557Y294761I1388J2503D01*
G01X1098722Y294691D01*
X1098724Y294695D01*
X1106601Y290757D01*
X1106599Y290753D01*
X1106767Y290654D01*
G02X1104199Y285554I-1453J-2465D01*
G37*
G36*
G01Y222562D02*
X1104034Y222632D01*
X1104032Y222628D01*
X1096156Y226566D01*
Y226574D01*
X1096053Y226631D01*
G02X1098557Y231769I1388J2503D01*
G01X1098722Y231699D01*
X1098724Y231703D01*
X1106601Y227765D01*
X1106599Y227761D01*
X1106767Y227662D01*
G02X1104199Y222562I-1453J-2465D01*
G37*
G36*
G01X1113922Y219793D02*
X1121763Y223713D01*
X1121764Y223714D01*
G02X1124266Y218790I1267J-2454D01*
G01X1116392Y214853D01*
G02X1113922Y219793I-1235J2470D01*
G37*
G36*
G01Y235541D02*
X1121763Y239461D01*
X1121764Y239462D01*
G02X1124266Y234538I1267J-2454D01*
G01X1116392Y230601D01*
G02X1113922Y235541I-1235J2470D01*
G37*
G36*
G01Y251289D02*
X1121763Y255209D01*
X1121764Y255210D01*
G02X1124266Y250286I1267J-2454D01*
G01X1116392Y246349D01*
G02X1113922Y251289I-1235J2470D01*
G37*
G36*
G01X1104199Y254058D02*
X1104034Y254128D01*
X1104032Y254124D01*
X1096156Y258062D01*
Y258070D01*
X1096053Y258127D01*
G02X1098557Y263265I1388J2503D01*
G01X1098722Y263195D01*
X1098724Y263199D01*
X1106601Y259261D01*
X1106599Y259257D01*
X1106767Y259158D01*
G02X1104199Y254058I-1453J-2465D01*
G37*
G36*
G01Y238310D02*
X1104034Y238380D01*
X1104032Y238376D01*
X1096156Y242314D01*
Y242322D01*
X1096053Y242379D01*
G02X1098557Y247517I1388J2503D01*
G01X1098722Y247447D01*
X1098724Y247451D01*
X1106601Y243513D01*
X1106599Y243509D01*
X1106767Y243410D01*
G02X1104199Y238310I-1453J-2465D01*
G37*
G36*
G01Y175318D02*
X1104034Y175388D01*
X1104032Y175384D01*
X1096156Y179322D01*
Y179330D01*
X1096053Y179387D01*
G02X1098557Y184525I1388J2503D01*
G01X1098722Y184455D01*
X1098724Y184459D01*
X1106601Y180521D01*
X1106599Y180517D01*
X1106767Y180418D01*
G02X1104199Y175318I-1453J-2465D01*
G37*
G36*
G01X1113922Y172549D02*
X1121763Y176469D01*
X1121764Y176470D01*
G02X1124266Y171546I1267J-2454D01*
G01X1116392Y167609D01*
G02X1113922Y172549I-1235J2470D01*
G37*
G36*
G01Y188297D02*
X1121763Y192217D01*
X1121764Y192218D01*
G02X1124266Y187294I1267J-2454D01*
G01X1116392Y183357D01*
G02X1113922Y188297I-1235J2470D01*
G37*
G36*
G01X1104199Y206814D02*
X1104034Y206884D01*
X1104032Y206880D01*
X1096156Y210818D01*
Y210826D01*
X1096053Y210883D01*
G02X1098557Y216021I1388J2503D01*
G01X1098722Y215951D01*
X1098724Y215955D01*
X1106601Y212017D01*
X1106599Y212013D01*
X1106767Y211914D01*
G02X1104199Y206814I-1453J-2465D01*
G37*
G36*
G01X1113922Y204045D02*
X1121763Y207965D01*
X1121764Y207966D01*
G02X1124266Y203042I1267J-2454D01*
G01X1116392Y199105D01*
G02X1113922Y204045I-1235J2470D01*
G37*
G36*
G01X1104199Y191066D02*
X1104034Y191136D01*
X1104032Y191132D01*
X1096156Y195070D01*
Y195078D01*
X1096053Y195135D01*
G02X1098557Y200273I1388J2503D01*
G01X1098722Y200203D01*
X1098724Y200207D01*
X1106601Y196269D01*
X1106599Y196265D01*
X1106767Y196166D01*
G02X1104199Y191066I-1453J-2465D01*
G37*
G36*
G01X1124320Y139943D02*
X1116446Y136006D01*
G02X1113868Y141160I-1289J2577D01*
G01X1121741Y145097D01*
G02X1124320Y139943I1290J-2577D01*
G37*
G36*
G01X1113922Y156801D02*
X1121763Y160721D01*
X1121764Y160722D01*
G02X1124266Y155798I1267J-2454D01*
G01X1116392Y151861D01*
G02X1113922Y156801I-1235J2470D01*
G37*
G36*
G01X1104199Y143822D02*
X1104034Y143892D01*
X1104032Y143888D01*
X1096156Y147826D01*
Y147834D01*
X1096053Y147891D01*
G02X1098557Y153029I1388J2503D01*
G01X1098722Y152959D01*
X1098724Y152963D01*
X1106601Y149025D01*
X1106599Y149021D01*
X1106767Y148922D01*
G02X1104199Y143822I-1453J-2465D01*
G37*
G36*
G01Y159570D02*
X1104034Y159640D01*
X1104032Y159636D01*
X1096156Y163574D01*
Y163582D01*
X1096053Y163639D01*
G02X1098557Y168777I1388J2503D01*
G01X1098722Y168707D01*
X1098724Y168711D01*
X1106601Y164773D01*
X1106599Y164769D01*
X1106767Y164670D01*
G02X1104199Y159570I-1453J-2465D01*
G37*
G36*
G01X1098730Y50609D02*
X1106604Y46672D01*
G02X1104026Y41518I-1289J-2577D01*
G01X1096195Y45434D01*
X1096194D01*
G02X1098730Y50609I1248J2597D01*
G37*
G36*
G01X1104199Y65082D02*
X1104034Y65152D01*
X1104032Y65148D01*
X1096156Y69086D01*
Y69094D01*
X1096053Y69151D01*
G02X1098557Y74289I1388J2503D01*
G01X1098722Y74219D01*
X1098724Y74223D01*
X1106601Y70285D01*
X1106599Y70281D01*
X1106767Y70182D01*
G02X1104199Y65082I-1453J-2465D01*
G37*
G36*
G01X1075250Y1413872D02*
X1070749D01*
G02X1070750Y1416876I1J1502D01*
G01X1075250D01*
G02Y1413872I0J-1502D01*
G37*
G36*
G01Y1406786D02*
X1070749D01*
G02X1070750Y1409788I1J1501D01*
G01X1075250D01*
G02Y1406786I0J-1501D01*
G37*
G36*
G01Y1399700D02*
X1070749D01*
G02X1070750Y1402702I1J1501D01*
G01X1075250D01*
G02Y1399700I0J-1501D01*
G37*
G36*
G01Y1392612D02*
X1070749D01*
G02X1070750Y1395616I1J1502D01*
G01X1075250D01*
G02Y1392612I0J-1502D01*
G37*
G36*
G01Y1385526D02*
X1070749D01*
G02X1070750Y1388530I1J1502D01*
G01X1075250D01*
G02Y1385526I0J-1502D01*
G37*
G36*
G01Y1378440D02*
X1070749D01*
G02X1070750Y1381442I1J1501D01*
G01X1075250D01*
G02Y1378440I0J-1501D01*
G37*
G36*
G01Y1328824D02*
X1070749D01*
G02X1070750Y1331846I1J1511D01*
G01X1075250D01*
G02Y1328824I0J-1511D01*
G37*
G36*
G01Y1293390D02*
X1070749D01*
G02X1070750Y1296414I1J1512D01*
G01X1075250D01*
G02Y1293390I0J-1512D01*
G37*
G36*
G01Y1300476D02*
X1070749D01*
G02X1070750Y1303500I1J1512D01*
G01X1075250D01*
G02Y1300476I0J-1512D01*
G37*
G36*
G01Y1307564D02*
X1070749D01*
G02X1070750Y1310586I1J1511D01*
G01X1075250D01*
G02Y1307564I0J-1511D01*
G37*
G36*
G01Y1314650D02*
X1070749D01*
G02X1070750Y1317672I1J1511D01*
G01X1075250D01*
G02Y1314650I0J-1511D01*
G37*
G36*
G01Y1321736D02*
X1070749D01*
G02X1070750Y1324760I1J1512D01*
G01X1075250D01*
G02Y1321736I0J-1512D01*
G37*
G36*
G01Y1229610D02*
X1070749D01*
G02X1070750Y1232634I1J1512D01*
G01X1075250D01*
G02Y1229610I0J-1512D01*
G37*
G36*
G01Y1236698D02*
X1070749D01*
G02X1070750Y1239720I1J1511D01*
G01X1075250D01*
G02Y1236698I0J-1511D01*
G37*
G36*
G01Y1243784D02*
X1070749D01*
G02X1070750Y1246806I1J1511D01*
G01X1075250D01*
G02Y1243784I0J-1511D01*
G37*
G36*
G01Y1208350D02*
X1070749D01*
G02X1070750Y1211374I1J1512D01*
G01X1075250D01*
G02Y1208350I0J-1512D01*
G37*
G36*
G01Y1215438D02*
X1070749D01*
G02X1070750Y1218460I1J1511D01*
G01X1075250D01*
G02Y1215438I0J-1511D01*
G37*
G36*
G01Y1222524D02*
X1070749D01*
G02X1070750Y1225546I1J1511D01*
G01X1075250D01*
G02Y1222524I0J-1511D01*
G37*
G36*
G01X956156Y708159D02*
X948315Y704239D01*
X948314Y704238D01*
G02X945812Y709162I-1267J2454D01*
G01X953686Y713099D01*
G02X956156Y708159I1235J-2470D01*
G37*
G36*
G01Y660915D02*
X948315Y656995D01*
X948314Y656994D01*
G02X945812Y661918I-1267J2454D01*
G01X953686Y665855D01*
G02X956156Y660915I1235J-2470D01*
G37*
G36*
G01Y692411D02*
X948315Y688491D01*
X948314Y688490D01*
G02X945812Y693414I-1267J2454D01*
G01X953686Y697351D01*
G02X956156Y692411I1235J-2470D01*
G37*
G36*
G01Y676663D02*
X948315Y672743D01*
X948314Y672742D01*
G02X945812Y677666I-1267J2454D01*
G01X953686Y681603D01*
G02X956156Y676663I1235J-2470D01*
G37*
G36*
G01X956210Y645060D02*
X948337Y641123D01*
G02X945758Y646277I-1290J2577D01*
G01X953632Y650214D01*
G02X956210Y645060I1289J-2577D01*
G37*
G36*
G01X945758Y630529D02*
X953631Y634466D01*
G02X956210Y629312I1290J-2577D01*
G01X948336Y625375D01*
G02X945758Y630529I-1289J2577D01*
G37*
G36*
G01Y614781D02*
X953631Y618718D01*
G02X956210Y613564I1290J-2577D01*
G01X948336Y609627D01*
G02X945758Y614781I-1289J2577D01*
G37*
G36*
G01X956210Y597816D02*
X948337Y593879D01*
G02X945758Y599033I-1290J2577D01*
G01X953632Y602970D01*
G02X956210Y597816I1289J-2577D01*
G37*
G36*
G01X956223Y503301D02*
X948392Y499386D01*
G02X945745Y504572I-1345J2582D01*
G01X953619Y508509D01*
G02X956223Y503301I1302J-2604D01*
G37*
G36*
G01X945745Y488824D02*
X953576Y492739D01*
G02X956223Y487553I1345J-2582D01*
G01X948349Y483616D01*
G02X945745Y488824I-1302J2604D01*
G37*
G36*
G01X945758Y473049D02*
X953631Y476986D01*
G02X956210Y471832I1290J-2577D01*
G01X948336Y467895D01*
G02X945758Y473049I-1289J2577D01*
G37*
G36*
G01X956210Y456084D02*
X948337Y452147D01*
G02X945758Y457301I-1290J2577D01*
G01X953632Y461238D01*
G02X956210Y456084I1289J-2577D01*
G37*
G36*
G01X945812Y314281D02*
X953653Y318201D01*
X953654Y318202D01*
G02X956156Y313278I1267J-2454D01*
G01X948282Y309341D01*
G02X945812Y314281I-1235J2470D01*
G37*
G36*
G01X956156Y329026D02*
X948315Y325106D01*
X948314Y325105D01*
G02X945812Y330029I-1267J2454D01*
G01X953686Y333966D01*
G02X956156Y329026I1235J-2470D01*
G37*
G36*
G01Y266034D02*
X948315Y262114D01*
X948314Y262113D01*
G02X945812Y267037I-1267J2454D01*
G01X953686Y270974D01*
G02X956156Y266034I1235J-2470D01*
G37*
G36*
G01X945812Y282785D02*
X953653Y286705D01*
X953654Y286706D01*
G02X956156Y281782I1267J-2454D01*
G01X948282Y277845D01*
G02X945812Y282785I-1235J2470D01*
G37*
G36*
G01Y298533D02*
X953653Y302453D01*
X953654Y302454D01*
G02X956156Y297530I1267J-2454D01*
G01X948282Y293593D01*
G02X945812Y298533I-1235J2470D01*
G37*
G36*
G01X956156Y218790D02*
X948315Y214870D01*
X948314Y214869D01*
G02X945812Y219793I-1267J2454D01*
G01X953686Y223730D01*
G02X956156Y218790I1235J-2470D01*
G37*
G36*
G01Y234538D02*
X948315Y230618D01*
X948314Y230617D01*
G02X945812Y235541I-1267J2454D01*
G01X953686Y239478D01*
G02X956156Y234538I1235J-2470D01*
G37*
G36*
G01Y250286D02*
X948315Y246366D01*
X948314Y246365D01*
G02X945812Y251289I-1267J2454D01*
G01X953686Y255226D01*
G02X956156Y250286I1235J-2470D01*
G37*
G36*
G01Y171546D02*
X948315Y167626D01*
X948314Y167625D01*
G02X945812Y172549I-1267J2454D01*
G01X953686Y176486D01*
G02X956156Y171546I1235J-2470D01*
G37*
G36*
G01Y187294D02*
X948315Y183374D01*
X948314Y183373D01*
G02X945812Y188297I-1267J2454D01*
G01X953686Y192234D01*
G02X956156Y187294I1235J-2470D01*
G37*
G36*
G01X945812Y204045D02*
X953653Y207965D01*
X953654Y207966D01*
G02X956156Y203042I1267J-2454D01*
G01X948282Y199105D01*
G02X945812Y204045I-1235J2470D01*
G37*
G36*
G01X945762Y141151D02*
X953636Y145088D01*
G02X956206Y139952I1285J-2568D01*
G01X948332Y136015D01*
G02X945762Y141151I-1285J2568D01*
G37*
G36*
G01X956156Y155798D02*
X948315Y151878D01*
X948314Y151877D01*
G02X945812Y156801I-1267J2454D01*
G01X953686Y160738D01*
G02X956156Y155798I1235J-2470D01*
G37*
G36*
G01X936089Y696183D02*
X935924Y696253D01*
X935922Y696249D01*
X928046Y700187D01*
Y700195D01*
X927943Y700252D01*
G02X930447Y705390I1388J2503D01*
G01X930612Y705320D01*
X930614Y705324D01*
X938491Y701386D01*
X938489Y701382D01*
X938657Y701283D01*
G02X936089Y696183I-1453J-2465D01*
G37*
G36*
G01Y680435D02*
X935924Y680505D01*
X935922Y680501D01*
X928046Y684439D01*
Y684447D01*
X927943Y684504D01*
G02X930447Y689642I1388J2503D01*
G01X930612Y689572D01*
X930614Y689576D01*
X938491Y685638D01*
X938489Y685634D01*
X938657Y685535D01*
G02X936089Y680435I-1453J-2465D01*
G37*
G36*
G01Y664687D02*
X935924Y664757D01*
X935922Y664753D01*
X928046Y668691D01*
Y668699D01*
X927943Y668756D01*
G02X930447Y673894I1388J2503D01*
G01X930612Y673824D01*
X930614Y673828D01*
X938491Y669890D01*
X938489Y669886D01*
X938657Y669787D01*
G02X936089Y664687I-1453J-2465D01*
G37*
G36*
G01Y648939D02*
X935924Y649009D01*
X935922Y649005D01*
X928046Y652943D01*
Y652951D01*
X927943Y653008D01*
G02X930447Y658146I1388J2503D01*
G01X930612Y658076D01*
X930614Y658080D01*
X938491Y654142D01*
X938489Y654138D01*
X938657Y654039D01*
G02X936089Y648939I-1453J-2465D01*
G37*
G36*
G01X935916Y601753D02*
X928085Y605669D01*
X928084D01*
G02X930620Y610844I1248J2597D01*
G01X938494Y606907D01*
G02X935916Y601753I-1289J-2577D01*
G37*
G36*
G01Y633249D02*
X928085Y637165D01*
X928084D01*
G02X930620Y642340I1248J2597D01*
G01X938494Y638403D01*
G02X935916Y633249I-1289J-2577D01*
G37*
G36*
G01Y617501D02*
X928085Y621417D01*
X928084D01*
G02X930620Y626592I1248J2597D01*
G01X938494Y622655D01*
G02X935916Y617501I-1289J-2577D01*
G37*
G36*
G01Y586005D02*
X928085Y589921D01*
X928084D01*
G02X930620Y595096I1248J2597D01*
G01X938494Y591159D01*
G02X935916Y586005I-1289J-2577D01*
G37*
G36*
G01Y507265D02*
X928085Y511181D01*
X928084D01*
G02X930620Y516356I1248J2597D01*
G01X938494Y512419D01*
G02X935916Y507265I-1289J-2577D01*
G37*
G36*
G01X936089Y538703D02*
X935924Y538773D01*
X935922Y538769D01*
X928046Y542707D01*
Y542715D01*
X927943Y542772D01*
G02X930447Y547910I1388J2503D01*
G01X930612Y547840D01*
X930614Y547844D01*
X938491Y543906D01*
X938489Y543902D01*
X938657Y543803D01*
G02X936089Y538703I-1453J-2465D01*
G37*
G36*
G01X935916Y491517D02*
X928085Y495433D01*
X928084D01*
G02X930620Y500608I1248J2597D01*
G01X938494Y496671D01*
G02X935916Y491517I-1289J-2577D01*
G37*
G36*
G01X930620Y484860D02*
X938451Y480944D01*
X938452D01*
G02X935916Y475769I-1248J-2597D01*
G01X928042Y479706D01*
G02X930620Y484860I1289J2577D01*
G37*
G36*
G01X935916Y460021D02*
X928085Y463937D01*
X928084D01*
G02X930620Y469112I1248J2597D01*
G01X938494Y465175D01*
G02X935916Y460021I-1289J-2577D01*
G37*
G36*
G01Y444273D02*
X928085Y448189D01*
X928084D01*
G02X930620Y453364I1248J2597D01*
G01X938494Y449427D01*
G02X935916Y444273I-1289J-2577D01*
G37*
G36*
G01X936089Y317050D02*
X935924Y317120D01*
X935922Y317116D01*
X928046Y321054D01*
Y321062D01*
X927943Y321119D01*
G02X930447Y326257I1388J2503D01*
G01X930612Y326187D01*
X930614Y326191D01*
X938491Y322253D01*
X938489Y322249D01*
X938657Y322150D01*
G02X936089Y317050I-1453J-2465D01*
G37*
G36*
G01Y269806D02*
X935924Y269876D01*
X935922Y269872D01*
X928046Y273810D01*
Y273818D01*
X927943Y273875D01*
G02X930447Y279013I1388J2503D01*
G01X930612Y278943D01*
X930614Y278947D01*
X938491Y275009D01*
X938489Y275005D01*
X938657Y274906D01*
G02X936089Y269806I-1453J-2465D01*
G37*
G36*
G01Y301302D02*
X935924Y301372D01*
X935922Y301368D01*
X928046Y305306D01*
Y305314D01*
X927943Y305371D01*
G02X930447Y310509I1388J2503D01*
G01X930612Y310439D01*
X930614Y310443D01*
X938491Y306505D01*
X938489Y306501D01*
X938657Y306402D01*
G02X936089Y301302I-1453J-2465D01*
G37*
G36*
G01Y285554D02*
X935924Y285624D01*
X935922Y285620D01*
X928046Y289558D01*
Y289566D01*
X927943Y289623D01*
G02X930447Y294761I1388J2503D01*
G01X930612Y294691D01*
X930614Y294695D01*
X938491Y290757D01*
X938489Y290753D01*
X938657Y290654D01*
G02X936089Y285554I-1453J-2465D01*
G37*
G36*
G01Y222562D02*
X935924Y222632D01*
X935922Y222628D01*
X928046Y226566D01*
Y226574D01*
X927943Y226631D01*
G02X930447Y231769I1388J2503D01*
G01X930612Y231699D01*
X930614Y231703D01*
X938491Y227765D01*
X938489Y227761D01*
X938657Y227662D01*
G02X936089Y222562I-1453J-2465D01*
G37*
G36*
G01Y254058D02*
X935924Y254128D01*
X935922Y254124D01*
X928045Y258062D01*
X928047Y258066D01*
X927879Y258165D01*
G02X930447Y263265I1453J2465D01*
G01X930612Y263195D01*
X930614Y263199D01*
X938490Y259261D01*
Y259253D01*
X938593Y259196D01*
G02X936089Y254058I-1388J-2503D01*
G37*
G36*
G01Y238310D02*
X935924Y238380D01*
X935922Y238376D01*
X928046Y242314D01*
Y242322D01*
X927943Y242379D01*
G02X930447Y247517I1388J2503D01*
G01X930612Y247447D01*
X930614Y247451D01*
X938491Y243513D01*
X938489Y243509D01*
X938657Y243410D01*
G02X936089Y238310I-1453J-2465D01*
G37*
G36*
G01Y175318D02*
X935924Y175388D01*
X935922Y175384D01*
X928046Y179322D01*
Y179330D01*
X927943Y179387D01*
G02X930447Y184525I1388J2503D01*
G01X930612Y184455D01*
X930614Y184459D01*
X938491Y180521D01*
X938489Y180517D01*
X938657Y180418D01*
G02X936089Y175318I-1453J-2465D01*
G37*
G36*
G01Y191066D02*
X935924Y191136D01*
X935922Y191132D01*
X928046Y195070D01*
Y195078D01*
X927943Y195135D01*
G02X930447Y200273I1388J2503D01*
G01X930612Y200203D01*
X930614Y200207D01*
X938491Y196269D01*
X938489Y196265D01*
X938657Y196166D01*
G02X936089Y191066I-1453J-2465D01*
G37*
G36*
G01Y206814D02*
X935924Y206884D01*
X935922Y206880D01*
X928046Y210818D01*
Y210826D01*
X927943Y210883D01*
G02X930447Y216021I1388J2503D01*
G01X930612Y215951D01*
X930614Y215955D01*
X938491Y212017D01*
X938489Y212013D01*
X938657Y211914D01*
G02X936089Y206814I-1453J-2465D01*
G37*
G36*
G01Y159570D02*
X935924Y159640D01*
X935922Y159636D01*
X928046Y163574D01*
Y163582D01*
X927943Y163639D01*
G02X930447Y168777I1388J2503D01*
G01X930612Y168707D01*
X930614Y168711D01*
X938491Y164773D01*
X938489Y164769D01*
X938657Y164670D01*
G02X936089Y159570I-1453J-2465D01*
G37*
G36*
G01Y143822D02*
X935924Y143892D01*
X935922Y143888D01*
X928046Y147826D01*
Y147834D01*
X927943Y147891D01*
G02X930447Y153029I1388J2503D01*
G01X930612Y152959D01*
X930614Y152963D01*
X938491Y149025D01*
X938489Y149021D01*
X938657Y148922D01*
G02X936089Y143822I-1453J-2465D01*
G37*
G36*
G01X930620Y50609D02*
X938494Y46672D01*
G02X935916Y41518I-1289J-2577D01*
G01X928085Y45434D01*
X928084D01*
G02X930620Y50609I1248J2597D01*
G37*
G36*
G01X936089Y65082D02*
X935924Y65152D01*
X935922Y65148D01*
X928046Y69086D01*
Y69094D01*
X927943Y69151D01*
G02X930447Y74289I1388J2503D01*
G01X930612Y74219D01*
X930614Y74223D01*
X938491Y70285D01*
X938489Y70281D01*
X938657Y70182D01*
G02X936089Y65082I-1453J-2465D01*
G37*
G36*
G01X878540Y1646457D02*
Y1640944D01*
G02X874216Y1640945I-2162J1D01*
G01Y1646457D01*
G02X878540I2162J0D01*
G37*
G36*
G01X871454Y1636221D02*
Y1630708D01*
G02X867130Y1630709I-2162J1D01*
G01Y1636221D01*
G02X871454I2162J0D01*
G37*
G36*
G01X864366Y1646457D02*
Y1640944D01*
G02X860044Y1640945I-2161J1D01*
G01Y1646457D01*
G02X864366I2161J0D01*
G37*
G36*
G01X857280Y1636221D02*
Y1630708D01*
G02X852956Y1630709I-2162J1D01*
G01Y1636221D01*
G02X857280I2162J0D01*
G37*
G36*
G01X850194Y1646457D02*
Y1640944D01*
G02X845870Y1640945I-2162J1D01*
G01Y1646457D01*
G02X850194I2162J0D01*
G37*
G36*
G01X878540Y1603937D02*
Y1598424D01*
G02X874216Y1598425I-2162J1D01*
G01Y1603937D01*
G02X878540I2162J0D01*
G37*
G36*
G01X871454Y1607874D02*
Y1602362D01*
G02X867130Y1602363I-2162J1D01*
G01Y1607874D01*
G02X871454I2162J0D01*
G37*
G36*
G01X864366Y1603937D02*
Y1598424D01*
G02X860044Y1598425I-2161J1D01*
G01Y1603937D01*
G02X864366I2161J0D01*
G37*
G36*
G01X857280Y1607874D02*
Y1602362D01*
G02X852956Y1602363I-2162J1D01*
G01Y1607874D01*
G02X857280I2162J0D01*
G37*
G36*
G01X850194Y1603937D02*
Y1598424D01*
G02X845870Y1598425I-2162J1D01*
G01Y1603937D01*
G02X850194I2162J0D01*
G37*
G36*
G01X843106Y1636221D02*
Y1630708D01*
G02X838784Y1630709I-2161J1D01*
G01Y1636221D01*
G02X843106I2161J0D01*
G37*
G36*
G01X836020Y1646457D02*
Y1640944D01*
G02X831698Y1640945I-2161J1D01*
G01Y1646457D01*
G02X836020I2161J0D01*
G37*
G36*
G01X828934Y1636221D02*
Y1630708D01*
G02X824610Y1630709I-2162J1D01*
G01Y1636221D01*
G02X828934I2162J0D01*
G37*
G36*
G01Y1622048D02*
Y1616535D01*
G02X824610Y1616536I-2162J1D01*
G01Y1622048D01*
G02X828934I2162J0D01*
G37*
G36*
G01X843106Y1607874D02*
Y1602362D01*
G02X838784Y1602363I-2161J1D01*
G01Y1607874D01*
G02X843106I2161J0D01*
G37*
G36*
G01X836020Y1603937D02*
Y1598424D01*
G02X831698Y1598425I-2161J1D01*
G01Y1603937D01*
G02X836020I2161J0D01*
G37*
G36*
G01X828934Y1607874D02*
Y1602362D01*
G02X824610Y1602363I-2162J1D01*
G01Y1607874D01*
G02X828934I2162J0D01*
G37*
G36*
G01X566532Y91930D02*
Y86417D01*
G02X562208Y86418I-2162J1D01*
G01Y91930D01*
G02X566532I2162J0D01*
G37*
G36*
G01Y77756D02*
Y72244D01*
G02X562208Y72245I-2162J1D01*
G01Y77756D01*
G02X566532I2162J0D01*
G37*
G36*
G01Y120276D02*
Y114763D01*
G02X562208Y114764I-2162J1D01*
G01Y120276D01*
G02X566532I2162J0D01*
G37*
G36*
G01X519688Y72245D02*
Y77757D01*
G02X524012Y77756I2162J-1D01*
G01Y72245D01*
G02X519688I-2162J0D01*
G37*
G36*
G01X516926Y87993D02*
Y82480D01*
G02X512602Y82481I-2162J1D01*
G01Y87993D01*
G02X516926I2162J0D01*
G37*
G36*
G01X524012Y91930D02*
Y86417D01*
G02X519688Y86418I-2162J1D01*
G01Y91930D01*
G02X524012I2162J0D01*
G37*
G36*
G01X531098Y87993D02*
Y82480D01*
G02X526776Y82481I-2161J1D01*
G01Y87993D01*
G02X531098I2161J0D01*
G37*
G36*
G01X538186Y91930D02*
Y86417D01*
G02X533862Y86418I-2162J1D01*
G01Y91930D01*
G02X538186I2162J0D01*
G37*
G36*
G01Y77756D02*
Y72244D01*
G02X533862Y72245I-2162J1D01*
G01Y77756D01*
G02X538186I2162J0D01*
G37*
G36*
G01Y120276D02*
Y114763D01*
G02X533862Y114764I-2162J1D01*
G01Y120276D01*
G02X538186I2162J0D01*
G37*
G36*
G01X545272Y87993D02*
Y82480D01*
G02X540948Y82481I-2162J1D01*
G01Y87993D01*
G02X545272I2162J0D01*
G37*
G36*
G01X552358Y91930D02*
Y86417D01*
G02X548036Y86418I-2161J1D01*
G01Y91930D01*
G02X552358I2161J0D01*
G37*
G36*
G01X559444Y87993D02*
Y82480D01*
G02X555122Y82481I-2161J1D01*
G01Y87993D01*
G02X559444I2161J0D01*
G37*
G36*
G01X552358Y77756D02*
Y72244D01*
G02X548036Y72245I-2161J1D01*
G01Y77756D01*
G02X552358I2161J0D01*
G37*
G36*
G01X516926Y73819D02*
Y68306D01*
G02X512602Y68307I-2162J1D01*
G01Y73819D01*
G02X516926I2162J0D01*
G37*
G36*
G01X531098D02*
Y68306D01*
G02X526776Y68307I-2161J1D01*
G01Y73819D01*
G02X531098I2161J0D01*
G37*
G36*
G01X545272D02*
Y68306D01*
G02X540948Y68307I-2162J1D01*
G01Y73819D01*
G02X545272I2162J0D01*
G37*
G36*
G01X559444D02*
Y68306D01*
G02X555122Y68307I-2161J1D01*
G01Y73819D01*
G02X559444I2161J0D01*
G37*
G36*
G01X481492Y91930D02*
Y86417D01*
G02X477170Y86418I-2161J1D01*
G01Y91930D01*
G02X481492I2161J0D01*
G37*
G36*
G01Y77756D02*
Y72244D01*
G02X477170Y72245I-2161J1D01*
G01Y77756D01*
G02X481492I2161J0D01*
G37*
G36*
G01X467318Y91930D02*
Y86417D01*
G02X462996Y86418I-2161J1D01*
G01Y91930D01*
G02X467318I2161J0D01*
G37*
G36*
G01X474406Y87993D02*
Y82480D01*
G02X470082Y82481I-2162J1D01*
G01Y87993D01*
G02X474406I2162J0D01*
G37*
G36*
G01X467318Y77756D02*
Y72244D01*
G02X462996Y72245I-2161J1D01*
G01Y77756D01*
G02X467318I2161J0D01*
G37*
G36*
G01X477160Y114764D02*
Y120277D01*
G02X481502Y120276I2171J-1D01*
G01Y114764D01*
G02X477160I-2171J0D01*
G37*
G36*
G01X474406Y73819D02*
Y68306D01*
G02X470082Y68307I-2162J1D01*
G01Y73819D01*
G02X474406I2162J0D01*
G37*
G36*
G01X438972Y77756D02*
Y72244D01*
G02X434650Y72245I-2161J1D01*
G01Y77756D01*
G02X438972I2161J0D01*
G37*
G36*
G01X431886Y87993D02*
Y82480D01*
G02X427562Y82481I-2162J1D01*
G01Y87993D01*
G02X431886I2162J0D01*
G37*
G36*
G01X438972Y91930D02*
Y86417D01*
G02X434650Y86418I-2161J1D01*
G01Y91930D01*
G02X438972I2161J0D01*
G37*
G36*
G01X446060Y87993D02*
Y82480D01*
G02X441736Y82481I-2162J1D01*
G01Y87993D01*
G02X446060I2162J0D01*
G37*
G36*
G01X453146Y91930D02*
Y86417D01*
G02X448822Y86418I-2162J1D01*
G01Y91930D01*
G02X453146I2162J0D01*
G37*
G36*
G01X460232Y87993D02*
Y82480D01*
G02X455910Y82481I-2161J1D01*
G01Y87993D01*
G02X460232I2161J0D01*
G37*
G36*
G01X453146Y77756D02*
Y72244D01*
G02X448822Y72245I-2162J1D01*
G01Y77756D01*
G02X453146I2162J0D01*
G37*
G36*
G01X460232Y116339D02*
Y110826D01*
G02X455910Y110827I-2161J1D01*
G01Y116339D01*
G02X460232I2161J0D01*
G37*
G36*
G01X431886Y73819D02*
Y68306D01*
G02X427562Y68307I-2162J1D01*
G01Y73819D01*
G02X431886I2162J0D01*
G37*
G36*
G01X446060D02*
Y68306D01*
G02X441736Y68307I-2162J1D01*
G01Y73819D01*
G02X446060I2162J0D01*
G37*
G36*
G01X460232D02*
Y68306D01*
G02X455910Y68307I-2161J1D01*
G01Y73819D01*
G02X460232I2161J0D01*
G37*
G36*
G01X1898061Y1091290D02*
X1898062Y1091293D01*
Y1095715D01*
X1898061Y1095718D01*
G02X1901065I1502J36D01*
G01X1901064Y1095715D01*
Y1091293D01*
X1901065Y1091290D01*
G02X1898061I-1502J-36D01*
G37*
G36*
G01X1776852Y1095718D02*
Y1091290D01*
G02X1773848I-1502J-36D01*
G01Y1095718D01*
G02X1776852I1502J36D01*
G37*
G36*
G01X1652640D02*
Y1091290D01*
G02X1649636I-1502J-36D01*
G01Y1095718D01*
G02X1652640I1502J36D01*
G37*
G36*
G01X1525423Y1091290D02*
X1525424Y1091293D01*
Y1095715D01*
X1525423Y1095718D01*
G02X1528427I1502J36D01*
G01X1528426Y1095715D01*
Y1091293D01*
X1528427Y1091290D01*
G02X1525423I-1502J-36D01*
G37*
G36*
G01X1401211D02*
X1401212Y1091293D01*
Y1095715D01*
X1401211Y1095718D01*
G02X1404215I1502J36D01*
G01X1404214Y1095715D01*
Y1091293D01*
X1404215Y1091290D01*
G02X1401211I-1502J-36D01*
G37*
G36*
G01X1280002Y1095718D02*
Y1091290D01*
G02X1276998I-1502J-36D01*
G01Y1095718D01*
G02X1280002I1502J36D01*
G37*
G36*
G01X747549Y1091290D02*
X747550Y1091293D01*
Y1095715D01*
X747549Y1095718D01*
G02X750553I1502J36D01*
G01X750552Y1095715D01*
Y1091293D01*
X750553Y1091290D01*
G02X747549I-1502J-36D01*
G37*
G36*
G01X626340Y1095718D02*
Y1091290D01*
G02X623336I-1502J-36D01*
G01Y1095718D01*
G02X626340I1502J36D01*
G37*
G36*
G01X499123Y1091290D02*
X499124Y1091293D01*
Y1095715D01*
X499123Y1095718D01*
G02X502127I1502J36D01*
G01X502126Y1095715D01*
Y1091293D01*
X502127Y1091290D01*
G02X499123I-1502J-36D01*
G37*
G36*
G01X374911D02*
X374912Y1091293D01*
Y1095715D01*
X374911Y1095718D01*
G02X377915I1502J36D01*
G01X377914Y1095715D01*
Y1091293D01*
X377915Y1091290D01*
G02X374911I-1502J-36D01*
G37*
G36*
G01X253702Y1095718D02*
Y1091290D01*
G02X250698I-1502J-36D01*
G01Y1095718D01*
G02X253702I1502J36D01*
G37*
G36*
G01X129490D02*
Y1091290D01*
G02X126486I-1502J-36D01*
G01Y1095718D01*
G02X129490I1502J36D01*
G37*
G36*
G01X1879361Y1076290D02*
X1879362Y1076293D01*
Y1080715D01*
X1879361Y1080718D01*
G02X1882365I1502J36D01*
G01X1882364Y1080715D01*
Y1076293D01*
X1882365Y1076290D01*
G02X1879361I-1502J-36D01*
G37*
G36*
G01X1758152Y1080718D02*
Y1076290D01*
G02X1755148I-1502J-36D01*
G01Y1080718D01*
G02X1758152I1502J36D01*
G37*
G36*
G01X1633940D02*
Y1076290D01*
G02X1630936I-1502J-36D01*
G01Y1080718D01*
G02X1633940I1502J36D01*
G37*
G36*
G01X1506723Y1076290D02*
X1506724Y1076293D01*
Y1080715D01*
X1506723Y1080718D01*
G02X1509727I1502J36D01*
G01X1509726Y1080715D01*
Y1076293D01*
X1509727Y1076290D01*
G02X1506723I-1502J-36D01*
G37*
G36*
G01X1382511D02*
X1382512Y1076293D01*
Y1080715D01*
X1382511Y1080718D01*
G02X1385515I1502J36D01*
G01X1385514Y1080715D01*
Y1076293D01*
X1385515Y1076290D01*
G02X1382511I-1502J-36D01*
G37*
G36*
G01X1898061Y638534D02*
X1898062Y638537D01*
Y642959D01*
X1898061Y642962D01*
G02X1901065I1502J36D01*
G01X1901064Y642959D01*
Y638537D01*
X1901065Y638534D01*
G02X1898061I-1502J-36D01*
G37*
G36*
G01X1726852Y642962D02*
Y638534D01*
G02X1723848I-1502J-36D01*
G01Y642962D01*
G02X1726852I1502J36D01*
G37*
G36*
G01X1652640D02*
Y638534D01*
G02X1649636I-1502J-36D01*
G01Y642962D01*
G02X1652640I1502J36D01*
G37*
G36*
G01X1525423Y638534D02*
X1525424Y638537D01*
Y642959D01*
X1525423Y642962D01*
G02X1528427I1502J36D01*
G01X1528426Y642959D01*
Y638537D01*
X1528427Y638534D01*
G02X1525423I-1502J-36D01*
G37*
G36*
G01X1401211D02*
X1401212Y638537D01*
Y642959D01*
X1401211Y642962D01*
G02X1404215I1502J36D01*
G01X1404214Y642959D01*
Y638537D01*
X1404215Y638534D01*
G02X1401211I-1502J-36D01*
G37*
G36*
G01X1280002Y642962D02*
Y638534D01*
G02X1276998I-1502J-36D01*
G01Y642962D01*
G02X1280002I1502J36D01*
G37*
G36*
G01X747549Y638534D02*
X747550Y638537D01*
Y642959D01*
X747549Y642962D01*
G02X750553I1502J36D01*
G01X750552Y642959D01*
Y638537D01*
X750553Y638534D01*
G02X747549I-1502J-36D01*
G37*
G36*
G01X626340Y642962D02*
Y638534D01*
G02X623336I-1502J-36D01*
G01Y642962D01*
G02X626340I1502J36D01*
G37*
G36*
G01X499123Y638534D02*
X499124Y638537D01*
Y642959D01*
X499123Y642962D01*
G02X502127I1502J36D01*
G01X502126Y642959D01*
Y638537D01*
X502127Y638534D01*
G02X499123I-1502J-36D01*
G37*
G36*
G01X374911D02*
X374912Y638537D01*
Y642959D01*
X374911Y642962D01*
G02X377915I1502J36D01*
G01X377914Y642959D01*
Y638537D01*
X377915Y638534D01*
G02X374911I-1502J-36D01*
G37*
G36*
G01X253702Y642962D02*
Y638534D01*
G02X250698I-1502J-36D01*
G01Y642962D01*
G02X253702I1502J36D01*
G37*
G36*
G01X129490D02*
Y638534D01*
G02X126486I-1502J-36D01*
G01Y642962D01*
G02X129490I1502J36D01*
G37*
G36*
G01X1879361Y623534D02*
X1879362Y623537D01*
Y627959D01*
X1879361Y627962D01*
G02X1882365I1502J36D01*
G01X1882364Y627959D01*
Y623537D01*
X1882365Y623534D01*
G02X1879361I-1502J-36D01*
G37*
G36*
G01X1733152Y627962D02*
Y623534D01*
G02X1730148I-1502J-36D01*
G01Y627962D01*
G02X1733152I1502J36D01*
G37*
G36*
G01X1633940D02*
Y623534D01*
G02X1630936I-1502J-36D01*
G01Y627962D01*
G02X1633940I1502J36D01*
G37*
G36*
G01X1506723Y623534D02*
X1506724Y623537D01*
Y627959D01*
X1506723Y627962D01*
G02X1509727I1502J36D01*
G01X1509726Y627959D01*
Y623537D01*
X1509727Y623534D01*
G02X1506723I-1502J-36D01*
G37*
G36*
G01X1382511D02*
X1382512Y623537D01*
Y627959D01*
X1382511Y627962D01*
G02X1385515I1502J36D01*
G01X1385514Y627959D01*
Y623537D01*
X1385515Y623534D01*
G02X1382511I-1502J-36D01*
G37*
G36*
G01X1261302Y627962D02*
Y623534D01*
G02X1258298I-1502J-36D01*
G01Y627962D01*
G02X1261302I1502J36D01*
G37*
G36*
G01X1898061Y185778D02*
X1898062Y185781D01*
Y190203D01*
X1898061Y190206D01*
G02X1901065I1502J36D01*
G01X1901064Y190203D01*
Y185781D01*
X1901065Y185778D01*
G02X1898061I-1502J-36D01*
G37*
G36*
G01X1776852Y190206D02*
Y185778D01*
G02X1773848I-1502J-36D01*
G01Y190206D01*
G02X1776852I1502J36D01*
G37*
G36*
G01X1652640D02*
Y185778D01*
G02X1649636I-1502J-36D01*
G01Y190206D01*
G02X1652640I1502J36D01*
G37*
G36*
G01X1525423Y185778D02*
X1525424Y185781D01*
Y190203D01*
X1525423Y190206D01*
G02X1528427I1502J36D01*
G01X1528426Y190203D01*
Y185781D01*
X1528427Y185778D01*
G02X1525423I-1502J-36D01*
G37*
G36*
G01X747549D02*
X747550Y185781D01*
Y190203D01*
X747549Y190206D01*
G02X750553I1502J36D01*
G01X750552Y190203D01*
Y185781D01*
X750553Y185778D01*
G02X747549I-1502J-36D01*
G37*
G36*
G01X626340Y190206D02*
Y185778D01*
G02X623336I-1502J-36D01*
G01Y190206D01*
G02X626340I1502J36D01*
G37*
G36*
G01X499123Y185778D02*
X499124Y185781D01*
Y190203D01*
X499123Y190206D01*
G02X502127I1502J36D01*
G01X502126Y190203D01*
Y185781D01*
X502127Y185778D01*
G02X499123I-1502J-36D01*
G37*
G36*
G01X374911D02*
X374912Y185781D01*
Y190203D01*
X374911Y190206D01*
G02X377915I1502J36D01*
G01X377914Y190203D01*
Y185781D01*
X377915Y185778D01*
G02X374911I-1502J-36D01*
G37*
G36*
G01X253702Y190206D02*
Y185778D01*
G02X250698I-1502J-36D01*
G01Y190206D01*
G02X253702I1502J36D01*
G37*
G36*
G01X129490D02*
Y185778D01*
G02X126486I-1502J-36D01*
G01Y190206D01*
G02X129490I1502J36D01*
G37*
G36*
G01X1270436Y184325D02*
X1270439Y184324D01*
X1274861D01*
X1274864Y184325D01*
G02Y181321I36J-1502D01*
G01X1274861Y181322D01*
X1270439D01*
X1270436Y181321D01*
G02Y184325I-36J1502D01*
G37*
G36*
G01X1511414Y180198D02*
X1506986D01*
G02Y183202I-36J1502D01*
G01X1511414D01*
G02Y180198I36J-1502D01*
G37*
G36*
G01X1879361Y170778D02*
X1879362Y170781D01*
Y175203D01*
X1879361Y175206D01*
G02X1882365I1502J36D01*
G01X1882364Y175203D01*
Y170781D01*
X1882365Y170778D01*
G02X1879361I-1502J-36D01*
G37*
G36*
G01X1758152Y175206D02*
Y170778D01*
G02X1755148I-1502J-36D01*
G01Y175206D01*
G02X1758152I1502J36D01*
G37*
G36*
G01X1633940D02*
Y170778D01*
G02X1630936I-1502J-36D01*
G01Y175206D01*
G02X1633940I1502J36D01*
G37*
G36*
G01X1256786Y169325D02*
X1256789Y169324D01*
X1261211D01*
X1261214Y169325D01*
G02Y166321I36J-1502D01*
G01X1261211Y166322D01*
X1256789D01*
X1256786Y166321D01*
G02Y169325I-36J1502D01*
G37*
G36*
G01X970474Y-46450D02*
Y-70079D01*
G02X919290I-25592J0D01*
G01Y-46456D01*
G02X960345Y-26064I25592J0D01*
G03X960986Y-25741I241J319D01*
G02X970115Y-39262I14801J151D01*
G03X969576Y-39736I-153J-369D01*
G02X970474Y-46450I-24694J-6720D01*
G37*
G36*
G01X558368Y829921D02*
G02I-55120J0D01*
G37*
G36*
G01X1729038D02*
G02I-55121J0D01*
G37*
G54D57*
X111024Y153681D03*
Y606437D03*
Y1059193D03*
X235236Y153681D03*
Y606437D03*
Y1059193D03*
X359449Y153681D03*
Y606437D03*
Y1059193D03*
X483661Y153681D03*
Y606437D03*
Y1059193D03*
X607874Y153681D03*
Y606437D03*
Y1059193D03*
X732087Y153681D03*
Y606437D03*
Y1059193D03*
X949902Y-115157D03*
X1281693Y153681D03*
Y606437D03*
Y1059193D03*
X1405906Y153681D03*
Y606437D03*
Y1059193D03*
X1530118Y153681D03*
Y606437D03*
Y1059193D03*
X1654331Y153681D03*
Y606437D03*
Y1059193D03*
X1778543Y153681D03*
Y606437D03*
Y1059193D03*
X1902756Y153681D03*
Y606437D03*
Y1059193D03*
G54D58*
X111024Y302303D03*
Y755059D03*
Y1207815D03*
X235236Y302303D03*
Y755059D03*
Y1207815D03*
X359449Y302303D03*
Y755059D03*
Y1207815D03*
X483661Y302303D03*
Y755059D03*
Y1207815D03*
X607874Y302303D03*
Y755059D03*
Y1207815D03*
X732087Y302303D03*
Y755059D03*
Y1207815D03*
X1098524Y-115157D03*
X1281693Y302303D03*
Y755059D03*
Y1207815D03*
X1405906Y302303D03*
Y755059D03*
Y1207815D03*
X1530118Y302303D03*
Y755059D03*
Y1207815D03*
X1654331Y302303D03*
Y755059D03*
Y1207815D03*
X1778543Y302303D03*
Y755059D03*
Y1207815D03*
X1902756Y302303D03*
Y755059D03*
Y1207815D03*
G54D59*
X79000Y1301900D03*
X1826700Y77600D03*
X1908500Y1346800D03*
G54D56*
X80019Y51968D03*
X127263Y20472D03*
X631200Y51968D03*
X678444Y20472D03*
X1250689Y51969D03*
X1297933Y20472D03*
X1801870Y51969D03*
X1849114Y20472D03*
G54D63*
X942126Y58465D03*
Y346457D03*
Y437598D03*
Y725590D03*
X1110236Y58465D03*
Y346457D03*
Y437598D03*
Y725590D03*
G54D60*
X173228Y1114173D03*
X670079D03*
X1343700D03*
X1840551D03*
G54D62*
X496653Y80906D03*
X1465157D03*
G54D55*
X103642Y36220D03*
X173228Y1062992D03*
X421653Y1141732D03*
X654822Y36220D03*
X670079Y1062992D03*
X1274311Y36220D03*
X1343701Y1062992D03*
X1592126Y1141732D03*
X1825492Y36220D03*
X1840551Y1062992D03*
G54D65*
X1903346Y803937D03*
G54D54*
X31496Y882677D03*
X168307Y646457D03*
X660236D03*
X718110Y820866D03*
X904921Y564961D03*
X1366142Y646457D03*
X1462992Y866929D03*
X1602756Y646457D03*
X1894685Y21654D03*
G54D64*
X975788Y564961D03*
G54D61*
X496654Y110551D03*
X1465158D03*
G54D48*
X1797933Y1282666D03*
Y829910D03*
Y377154D03*
X1549901Y1282666D03*
Y829910D03*
Y377154D03*
X796457Y735444D03*
Y263003D03*
X627263Y1282666D03*
Y829910D03*
Y377154D03*
X131201Y1282666D03*
Y377154D03*
G54D51*
X1102113Y1394115D03*
X1098176Y1401201D03*
X1102113Y1351595D03*
X1098176Y1330335D03*
Y1372855D03*
X1126522Y1330335D03*
X1130459Y1351595D03*
X1102113Y1280729D03*
X1098176Y1301989D03*
X1102113Y1309075D03*
Y1323249D03*
X1130459Y1280729D03*
X1098176Y1259469D03*
Y1231123D03*
X1102113Y1238209D03*
X1126522Y1259469D03*
X1098176Y1188603D03*
X1102113Y1209863D03*
X1098176Y1216949D03*
X1126522Y1188603D03*
X1102113Y1167343D03*
X1098176Y1160257D03*
G54D49*
X1301870Y1282666D03*
Y829910D03*
Y377154D03*
X1181890Y1559854D03*
X1181870Y969280D03*
X1181890Y555917D03*
X961418Y1429932D03*
Y1087413D03*
X379232Y1282666D03*
Y829910D03*
Y377154D03*
X131200Y829910D03*
G54D53*
X1126522Y1401201D03*
X1130459Y1394115D03*
X1126522Y1372855D03*
X1130459Y1323249D03*
Y1309075D03*
X1126522Y1301989D03*
X1130459Y1238209D03*
X1126522Y1231123D03*
Y1216949D03*
X1130459Y1209863D03*
Y1167343D03*
X1126522Y1160257D03*
X1098176Y1002765D03*
X1102113Y1024025D03*
X1098176Y1031111D03*
X1126522D03*
X1130459Y1024025D03*
X1126522Y1002765D03*
G54D50*
X1102113Y1379942D03*
X1098176Y1387028D03*
X1102113Y1408288D03*
Y1365768D03*
X1098176Y1358682D03*
Y1344508D03*
X1102113Y1337422D03*
X1130459D03*
X1126522Y1344508D03*
Y1358682D03*
X1130459Y1365768D03*
X1098176Y1287816D03*
X1102113Y1294902D03*
X1098176Y1316162D03*
Y1273642D03*
X1102113Y1266556D03*
Y1252382D03*
X1098176Y1245296D03*
X1126522D03*
X1130459Y1252382D03*
Y1266556D03*
X1126522Y1273642D03*
X1102113Y1195690D03*
Y1181516D03*
X1098176Y1202776D03*
X1102113Y1224036D03*
X1130459Y1181516D03*
Y1195690D03*
X1098176Y1174430D03*
X1126522D03*
X1116286Y1038198D03*
G54D52*
X1130459Y1408288D03*
X1126522Y1387028D03*
X1130459Y1379942D03*
X1126522Y1316162D03*
X1130459Y1294902D03*
X1126522Y1287816D03*
X1130459Y1224036D03*
X1126522Y1202776D03*
X1102113Y1038198D03*
X1130459D03*
X1098176Y988592D03*
X1102113Y995678D03*
Y1009852D03*
X1098176Y1016938D03*
X1126522D03*
X1130459Y1009852D03*
Y995678D03*
X1126522Y988592D03*
G54D24*
X127988Y190242D03*
Y185742D03*
Y638498D03*
Y642998D03*
Y1091254D03*
Y1095754D03*
X252200Y190242D03*
Y185742D03*
Y638498D03*
Y642998D03*
Y1091254D03*
Y1095754D03*
X376413Y190242D03*
Y185742D03*
Y638498D03*
Y642998D03*
Y1091254D03*
Y1095754D03*
X500625Y190242D03*
Y185742D03*
Y638498D03*
Y642998D03*
Y1091254D03*
Y1095754D03*
X624838Y190242D03*
Y185742D03*
Y638498D03*
Y642998D03*
Y1091254D03*
Y1095754D03*
X749051Y190242D03*
Y185742D03*
Y638498D03*
Y642998D03*
Y1091254D03*
Y1095754D03*
X1070750Y1224035D03*
X1075250D03*
X1070750Y1209862D03*
X1075250D03*
X1070750Y1216949D03*
X1075250D03*
X1070750Y1231122D03*
X1075250D03*
X1070750Y1238209D03*
X1075250D03*
X1070750Y1245295D03*
X1075250D03*
X1070750Y1301988D03*
X1075250D03*
X1070750Y1309075D03*
X1075250D03*
X1070750Y1316161D03*
X1075250D03*
X1070750Y1323248D03*
X1075250D03*
X1070750Y1294902D03*
X1075250D03*
X1070750Y1330335D03*
X1075250D03*
X1070750Y1387028D03*
X1075250D03*
X1070750Y1394114D03*
X1075250D03*
X1070750Y1401201D03*
X1075250D03*
X1070750Y1408287D03*
X1075250D03*
X1070750Y1415374D03*
X1075250D03*
X1070750Y1379941D03*
X1075250D03*
X1274900Y182823D03*
X1270400D03*
X1261250Y167823D03*
X1256750D03*
X1278500Y638498D03*
Y642998D03*
X1259800Y627998D03*
Y623498D03*
Y1080754D03*
Y1076254D03*
X1278500Y1091254D03*
Y1095754D03*
X1402713Y185742D03*
Y190242D03*
X1380963Y167823D03*
X1385463D03*
X1402713Y638498D03*
Y642998D03*
X1384013Y627998D03*
Y623498D03*
Y1080754D03*
Y1076254D03*
X1402713Y1091254D03*
Y1095754D03*
X1511450Y181700D03*
X1506950D03*
X1508225Y627998D03*
Y623498D03*
Y1080754D03*
Y1076254D03*
X1526925Y185742D03*
Y190242D03*
Y638498D03*
Y642998D03*
Y1091254D03*
Y1095754D03*
X1651138Y185742D03*
Y190242D03*
X1632438Y175242D03*
Y170742D03*
X1651138Y638498D03*
Y642998D03*
X1632438Y627998D03*
Y623498D03*
Y1080754D03*
Y1076254D03*
X1651138Y1091254D03*
Y1095754D03*
X1756650Y175242D03*
Y170742D03*
X1725350Y638498D03*
Y642998D03*
X1731650Y627998D03*
Y623498D03*
X1756650Y1080754D03*
Y1076254D03*
X1775350Y185742D03*
Y190242D03*
Y1091254D03*
Y1095754D03*
X1899563Y185742D03*
Y190242D03*
X1880863Y175242D03*
Y170742D03*
X1899563Y638498D03*
Y642998D03*
X1880863Y627998D03*
Y623498D03*
Y1080754D03*
Y1076254D03*
X1899563Y1091254D03*
Y1095754D03*
G54D44*
X1039845Y1467746D03*
X1026345D03*
X1030845D03*
X1035345D03*
X1039845Y1463246D03*
X1026345D03*
X1030845D03*
X1035345D03*
X1005400Y1463157D03*
X1000900D03*
X996400D03*
X1009900D03*
X1005400Y1467657D03*
X1000900D03*
X996400D03*
X1009900D03*
X1035345Y1476746D03*
X1030845D03*
X1026345D03*
X1039845D03*
Y1472246D03*
X1026345D03*
X1030845D03*
X1035345D03*
X1005400Y1472157D03*
X1000900D03*
X996400D03*
X1009900D03*
Y1476657D03*
X1005400D03*
X1000900D03*
X996400D03*
X1023583Y1489593D03*
X995783D03*
X1000500Y1511400D03*
X1036578Y1511210D03*
X1014690Y1511178D03*
X1010190D03*
X1005690D03*
X1031790Y1511078D03*
X1027290D03*
X1019600Y1511100D03*
X1023583Y1501593D03*
Y1507593D03*
Y1495593D03*
X995783D03*
Y1501593D03*
Y1507593D03*
X1040583Y1517883D03*
X1031799Y1534392D03*
X1031882Y1528985D03*
X1026459Y1528919D03*
X1026376Y1534326D03*
X1014867D03*
X1014950Y1528919D03*
X1020290Y1534392D03*
X1020373Y1528985D03*
X1040500Y1529290D03*
X1040583Y1523883D03*
X1062700Y1463100D03*
X1058200D03*
X1067200D03*
X1062700Y1467600D03*
X1058200D03*
X1067200D03*
X1053700Y1463100D03*
Y1467600D03*
X1062700Y1472100D03*
X1058200D03*
X1067200D03*
Y1476600D03*
X1058200D03*
X1062700D03*
X1053700Y1472100D03*
Y1476600D03*
X1078683Y1489593D03*
X1051383D03*
X1041810Y1511084D03*
X1055310D03*
X1059810D03*
X1064310D03*
X1068810D03*
X1073310D03*
X1078683Y1495593D03*
Y1501593D03*
Y1507593D03*
Y1516593D03*
X1051383Y1495593D03*
Y1501593D03*
Y1507593D03*
X1078683Y1522593D03*
G54D14*
X19712Y1176350D03*
X25000Y1190400D03*
X64487Y201761D03*
X53087Y179561D03*
X49937Y219661D03*
X54437D03*
X58937D03*
X47607Y527511D03*
X61834Y527515D03*
X72500Y508600D03*
X67500D03*
X53087Y632317D03*
X58937Y672417D03*
X54437D03*
X49937D03*
X64487Y654417D03*
X27143Y663071D03*
X27510Y688422D03*
X58175Y981325D03*
X67500Y961355D03*
X72500D03*
X58937Y1125173D03*
X54437D03*
X49937D03*
X64487Y1107173D03*
X53027Y1085073D03*
X39325Y1131400D03*
X26723Y1116038D03*
X36848Y1173600D03*
X27090Y1141389D03*
X31500Y1224000D03*
X39425Y1226200D03*
X30000Y1190400D03*
X37225Y1230100D03*
X45518Y1336366D03*
X41381Y1335567D03*
X95437Y176661D03*
Y181161D03*
X73937Y201661D03*
X78937D03*
X83937D03*
X88937D03*
X85146Y621637D03*
X95437Y633917D03*
X88937Y654417D03*
X83937D03*
X78937D03*
X73937D03*
X101403Y981195D03*
X97063Y973225D03*
X98563Y977225D03*
X114100Y1002600D03*
X99700Y991400D03*
X108063Y991925D03*
X114300Y992362D03*
X104230Y992209D03*
X95537Y1082173D03*
Y1086673D03*
X73937Y1107173D03*
X78937D03*
X83937D03*
X88937D03*
X142687Y248100D03*
X145437Y265561D03*
X166400Y579400D03*
X168103Y569195D03*
X163763Y561225D03*
X165263Y565225D03*
X150253Y709713D03*
X145437Y717617D03*
X142687Y700767D03*
X140364Y749807D03*
X137163Y987125D03*
X130463Y983925D03*
X133063Y1012725D03*
X137063Y993725D03*
X145363Y997741D03*
X131110Y993257D03*
X148400Y1086900D03*
X145437Y1165673D03*
X150862Y1152723D03*
X142687Y1153523D03*
X148300Y1228800D03*
X148311Y1182767D03*
X135422Y1190937D03*
X140422D03*
X163500Y1345200D03*
X188699Y200561D03*
X177399Y179661D03*
X198149Y201661D03*
X203149D03*
X208149D03*
X213149D03*
X174149Y219661D03*
X178649D03*
X183149D03*
X171861Y527469D03*
X186088Y527473D03*
X196712Y508600D03*
X191712D03*
X210263Y546725D03*
X180800Y590600D03*
X207313Y598113D03*
X203763Y581725D03*
X212063Y585741D03*
X197810Y581257D03*
X174763Y579925D03*
X203863Y575125D03*
X181000Y580362D03*
X170930Y580209D03*
X197163Y571925D03*
X185149Y617949D03*
X199763Y600725D03*
X210000Y650000D03*
X182259Y672559D03*
X177759D03*
X173259D03*
X198149Y654417D03*
X203149D03*
X208149D03*
X213149D03*
X199900Y923200D03*
X216712Y961155D03*
X188399Y1102873D03*
X183149Y1125173D03*
X178649D03*
X174149D03*
X177105Y1094839D03*
X195100Y1096800D03*
X198149Y1107173D03*
X203149D03*
X208149D03*
X213149D03*
X219749Y176661D03*
Y181361D03*
X266899Y248011D03*
X219749Y618917D03*
Y623417D03*
X258600Y715500D03*
X266899Y700767D03*
X264731Y749551D03*
X223100Y920600D03*
X239000Y985600D03*
X221712Y961155D03*
X252100Y990100D03*
X244600Y1004600D03*
X261100Y1005700D03*
X227063Y994925D03*
X219749Y1082173D03*
X264864Y1120500D03*
X219749Y1086873D03*
X264594Y1190768D03*
X259594D03*
X312079Y68379D03*
X303029Y68429D03*
X313628Y112926D03*
X303000Y73500D03*
X314370Y118452D03*
X314439Y133669D03*
X312912Y201661D03*
X301612Y179661D03*
X298362Y219661D03*
X302862D03*
X307362D03*
X269649Y266261D03*
X291601Y418503D03*
X292153Y486059D03*
X306388Y486022D03*
X296032Y527469D03*
X310259Y527473D03*
X293763Y582925D03*
X301612Y632417D03*
X307362Y672417D03*
X302862D03*
X298362D03*
X312912Y654417D03*
X274520Y709457D03*
X268100Y982300D03*
X273300Y981700D03*
X280800Y1011900D03*
X281200Y1033000D03*
X271100Y1063200D03*
X281500Y1036744D03*
X307362Y1125173D03*
X302862D03*
X298362D03*
X313232Y1106499D03*
X301327Y1085173D03*
X269649Y1165673D03*
X275385Y1152596D03*
X271165Y1147172D03*
X315500Y1216700D03*
X276100Y1229100D03*
X273243Y1182915D03*
X286925Y1201945D03*
X295900Y1339700D03*
X296100Y1335100D03*
X279900Y1328300D03*
X283700D03*
X286100Y1349659D03*
X292600Y1337367D03*
X289510Y1342259D03*
X354100Y62100D03*
X322500Y68345D03*
X334845Y58745D03*
X361776Y70842D03*
X335081Y104081D03*
X339219Y95188D03*
X339914Y82415D03*
X344304Y82439D03*
X345321Y102400D03*
X347647Y95614D03*
X353001Y114815D03*
X347881Y114881D03*
X351416Y95788D03*
X337641Y114910D03*
X334947Y94605D03*
X342761Y114861D03*
X350441Y117541D03*
X337721Y129821D03*
X323813Y118512D03*
X341114Y123622D03*
X345321Y118921D03*
X323813Y133722D03*
X344062Y176461D03*
X343962Y181161D03*
X322362Y201661D03*
X327362D03*
X332362D03*
X337362D03*
X320474Y379474D03*
X316534D03*
X320474Y363234D03*
X316534D03*
X320925Y485385D03*
X315925D03*
X320925Y508600D03*
X315925D03*
X333682Y621858D03*
X343862Y633917D03*
X322362Y654417D03*
X327362D03*
X332362D03*
X337362D03*
X320474Y832229D03*
X316534D03*
X320925Y938140D03*
X315600Y933600D03*
X335300Y926900D03*
X337100Y972100D03*
X320925Y961355D03*
X315925D03*
X344737Y995637D03*
X350673Y1031200D03*
X344062Y1082073D03*
Y1086773D03*
X322362Y1107173D03*
X327362D03*
X332362D03*
X337362D03*
X331679Y1175800D03*
X377144Y84720D03*
X377944Y95929D03*
X390412Y248011D03*
X386800Y263800D03*
X393862Y719917D03*
X398677Y709385D03*
X391112Y700767D03*
X388788Y749479D03*
X407714Y761291D03*
X398254Y763517D03*
X408672Y1008038D03*
X388888Y1118173D03*
X393679Y1157480D03*
X383191Y1170203D03*
X391112Y1153500D03*
X398527Y1188659D03*
X383849Y1190833D03*
X388849Y1191148D03*
X398527Y1233336D03*
X437124Y201661D03*
X429224Y176300D03*
X446951Y213656D03*
X451951D03*
X456951D03*
X431574Y219661D03*
X427074D03*
X422574D03*
X441645Y288847D03*
Y284647D03*
X456190Y354105D03*
X444687Y379474D03*
X440747D03*
X444687Y363234D03*
X440747D03*
X452800Y420912D03*
X418600Y445462D03*
X421700Y450200D03*
X445138Y487743D03*
X440138D03*
X447533Y475900D03*
X458679Y470700D03*
X450500Y459562D03*
X416303Y486022D03*
X430538Y485985D03*
X420182Y527432D03*
X434409Y527436D03*
X440138Y508600D03*
X445138D03*
X425824Y632317D03*
X457853Y622091D03*
X437224Y654417D03*
X431574Y672417D03*
X427074D03*
X422574D03*
X456574Y654417D03*
X451574D03*
X446574D03*
X444687Y832229D03*
X440747D03*
X444687Y816765D03*
X440747D03*
X445138Y938140D03*
X440138D03*
X435082Y915200D03*
X437600Y917800D03*
X445582Y925352D03*
X449137Y967757D03*
X440138Y961355D03*
X445138D03*
X429613Y1017920D03*
X432657Y1015102D03*
X442600Y998300D03*
X413000Y1054200D03*
X442473Y1068726D03*
X447173D03*
X456919Y1121725D03*
X447919D03*
X452419D03*
X441976Y1107576D03*
X446627Y1112973D03*
X441400Y1169400D03*
X416900Y1221800D03*
X412300Y1326200D03*
X415422Y1352000D03*
X422373Y1359747D03*
X418922Y1356522D03*
X462200Y173109D03*
X468472Y182441D03*
X461951Y213656D03*
X462133Y473300D03*
X481533Y480875D03*
X497351Y531531D03*
X501023Y534941D03*
X472022Y582062D03*
X468174Y633917D03*
X461574Y654417D03*
X465200Y1018200D03*
X506500Y1051900D03*
X504724Y1107073D03*
X505874Y1134773D03*
X506700Y1145973D03*
X508103Y1190557D03*
X509180Y145419D03*
X546009Y187821D03*
X539584Y184694D03*
X542155Y187543D03*
X557057Y220152D03*
X553674Y220121D03*
X550219Y220111D03*
X515324Y252511D03*
X553742Y267705D03*
X510700Y277200D03*
X534905Y354105D03*
X539350Y487659D03*
X534350D03*
X510621Y486059D03*
X524856Y486022D03*
X518700Y548700D03*
X553279Y523331D03*
X514500Y524469D03*
X528727Y524973D03*
X553279Y513331D03*
X530130Y547167D03*
X534350Y508600D03*
X539350D03*
X557279Y570331D03*
X527179Y568731D03*
X549937Y632317D03*
X555787Y672417D03*
X551287D03*
X546787D03*
X509996Y716996D03*
X522773Y709638D03*
X515324Y700667D03*
X512884Y749732D03*
X530800Y1028300D03*
X515800Y1028000D03*
X556022Y1042817D03*
X552436Y1042494D03*
X546787Y1125173D03*
X551287D03*
X555787D03*
X549773Y1085173D03*
X514474Y1107073D03*
X519474D03*
X524474D03*
X529474D03*
X509037Y1136700D03*
X524828Y1159231D03*
X522867Y1190284D03*
X513103Y1190557D03*
X522867Y1231097D03*
X520600Y1324100D03*
X536000Y1359826D03*
X541362D03*
X518397Y1360000D03*
X512900Y1345600D03*
X553587Y1346026D03*
X527000Y1340600D03*
X521500Y1342800D03*
X566271Y167387D03*
X561437Y197249D03*
X592767Y179277D03*
X598236Y181981D03*
X582697Y200744D03*
X577697D03*
X572697D03*
X587697D03*
X568899Y379474D03*
X564959D03*
X568899Y363234D03*
X564959D03*
X602379Y547831D03*
X570779Y542831D03*
X568779Y512831D03*
X575779D03*
X593079Y516531D03*
Y512531D03*
X585479Y537731D03*
Y543994D03*
X572229Y520081D03*
X580279Y512831D03*
X571408Y577450D03*
X584279Y577431D03*
X575779D03*
X579718D03*
X592779D03*
X588779D03*
X562279D03*
X567641Y577473D03*
X571529Y562951D03*
X579529D03*
X602779Y552331D03*
X592387Y629417D03*
Y634017D03*
X561437Y654417D03*
X585787D03*
X580787D03*
X575787D03*
X570787D03*
X568899Y832229D03*
X564959D03*
X593365Y877358D03*
X592614Y882300D03*
X569350Y941640D03*
X564350D03*
X569350Y961355D03*
X564350D03*
X571400Y1000100D03*
X592387Y1082173D03*
X561337Y1107173D03*
X592387Y1086873D03*
X570787Y1107173D03*
X575787D03*
X580787D03*
X585787D03*
X600640Y1171000D03*
X592400Y1214456D03*
X607929Y112329D03*
X619171D03*
X639537Y248011D03*
X642287Y266461D03*
X652663Y502400D03*
X647663D03*
X612000Y502300D03*
X624028Y503558D03*
X638263Y503494D03*
X615119Y551586D03*
X627000Y538581D03*
Y542909D03*
X609334Y538306D03*
Y543306D03*
X619560Y547201D03*
X627863Y522000D03*
X642509Y520667D03*
X652663Y516600D03*
X647663D03*
X615147Y565956D03*
X637213Y582155D03*
X623236Y562574D03*
X642287Y719817D03*
X647207Y709555D03*
X639537Y700767D03*
X637318Y749649D03*
X645200Y1067800D03*
X636803Y1167864D03*
X642942Y1156818D03*
X632603Y1136225D03*
X647716Y1154150D03*
X639537Y1153523D03*
X627632Y1217300D03*
X647126Y1189513D03*
X632316Y1190474D03*
X637316D03*
X687566Y109568D03*
X663449Y115606D03*
X690807Y103298D03*
X677450Y185669D03*
X685250Y199493D03*
X699950Y200846D03*
X694950D03*
X674313Y220374D03*
X669813D03*
X689232Y355251D03*
X693112Y385976D03*
X689172D03*
Y358978D03*
X658646Y515180D03*
X658681Y571798D03*
X654681D03*
X683341Y580479D03*
X689747D03*
X682000Y628449D03*
X685550Y654417D03*
X679929Y673058D03*
X675429D03*
X670929D03*
X700000Y654417D03*
X695000D03*
X658574Y930100D03*
X677457Y944796D03*
X688563Y961355D03*
X693563D03*
X663800Y1018300D03*
X682200Y1026500D03*
X674300Y1001620D03*
X685250Y1102873D03*
X680000Y1125173D03*
X675500D03*
X671000D03*
X674700Y1098500D03*
X695000Y1107173D03*
X700000D03*
X664000Y1278100D03*
X673000Y1354100D03*
X747242Y197553D03*
X717188Y176461D03*
X716600Y181161D03*
X709950Y200846D03*
X704950D03*
X705348Y478425D03*
X716600Y629417D03*
Y633917D03*
X710000Y654417D03*
X705000D03*
X724283Y860689D03*
X737984Y861689D03*
X741883Y861389D03*
X733883Y935689D03*
X736883Y938689D03*
Y929189D03*
Y933689D03*
X747383Y924689D03*
X733883Y940689D03*
X736462Y948996D03*
X736883Y943189D03*
X716600Y1081973D03*
Y1086673D03*
X705000Y1107173D03*
X710000D03*
X728174Y1275611D03*
X725678Y1272799D03*
X722790Y1270557D03*
X720446Y1267427D03*
X731500Y1277811D03*
X757020Y159692D03*
X758619Y168537D03*
X767405Y210364D03*
X763188Y172500D03*
X789739Y365493D03*
X754500Y668741D03*
X755000Y677700D03*
X765124Y864089D03*
X766707Y872260D03*
X762453Y872413D03*
X765025Y867802D03*
X757664Y868974D03*
X753893Y912630D03*
X776400Y956500D03*
X780800Y959300D03*
X786800Y1016000D03*
X784000Y1024000D03*
X759500Y1056100D03*
X779535Y1180469D03*
X792263Y1178661D03*
Y1174461D03*
Y1170261D03*
X752500Y1167500D03*
X756250Y1151750D03*
X784544Y1210178D03*
Y1205978D03*
X779535Y1193469D03*
Y1189269D03*
Y1184669D03*
X797177Y1189537D03*
X797225Y1185337D03*
X792263Y1182861D03*
X792336Y1319537D03*
X782230Y1323670D03*
X769728Y1325747D03*
X785340Y1320410D03*
X789549Y1322310D03*
X777009Y1322690D03*
X781290Y1328490D03*
X772900Y1328550D03*
X790290Y1328410D03*
X785640Y1328370D03*
X796848Y1469724D03*
X829921Y-458D03*
X825984D03*
X833724Y-3346D03*
X833671Y254D03*
X806299Y-458D03*
X802362D03*
X814173D03*
X810236D03*
X822047D03*
X818110D03*
X845661Y-3642D03*
X843463Y530D03*
X806314Y35952D03*
X802350Y35923D03*
X842470Y41295D03*
X841733Y36654D03*
X818300Y39845D03*
X814300D03*
Y43845D03*
X818300D03*
X810301Y78654D03*
X805301D03*
X802801Y75654D03*
X807801D03*
X812801D03*
X846400Y473900D03*
X839500Y508500D03*
X809015Y661000D03*
X804015D03*
X808920Y652340D03*
Y656460D03*
X806515Y664000D03*
X802036Y1164244D03*
X803438Y1139700D03*
X809600Y1236300D03*
X804600D03*
X802100Y1233300D03*
X807100D03*
X812100D03*
X806952Y1460496D03*
X806568Y1464275D03*
X802433Y1461619D03*
X800900Y1465234D03*
X800462Y1469231D03*
X834813Y1528889D03*
X834974Y1533243D03*
X886322Y69D03*
X867080Y393D03*
X886427Y3802D03*
X873892Y287D03*
X886418Y-7350D03*
X849484Y649D03*
X886351Y-3735D03*
X857513Y659D03*
X885448Y37380D03*
X877265Y52540D03*
X881265D03*
X885265D03*
X873265D03*
X869265D03*
X869459Y56626D03*
Y61626D03*
X869044Y66985D03*
X873044D03*
X877139Y66926D03*
X885265Y60540D03*
Y56540D03*
X881750Y37397D03*
X858496Y37121D03*
X854180Y36996D03*
X852995Y40965D03*
X856995D03*
X886073Y78824D03*
X885464Y83201D03*
X878549Y78905D03*
Y82905D03*
X869044Y70985D03*
X873044D03*
X882549Y76905D03*
Y80905D03*
X872796Y251714D03*
X881549Y326304D03*
X890982Y349498D03*
X874800Y355798D03*
X887100Y359100D03*
X887500Y378495D03*
X875132Y399200D03*
X878732D03*
Y395600D03*
X875132D03*
X878732Y392000D03*
X875132D03*
X880932Y406400D03*
Y402800D03*
X877332Y406400D03*
Y402800D03*
X874807Y375193D03*
X866276Y454900D03*
X866317Y446725D03*
X880932Y410000D03*
X877332D03*
X857300Y454300D03*
X862000Y453600D03*
X852000Y454200D03*
X866321Y451300D03*
X878500Y476000D03*
X878193Y467707D03*
X866278Y459562D03*
X870600Y476900D03*
X851800Y477200D03*
X874715Y707651D03*
X871115D03*
X867515D03*
X884700Y705200D03*
X881100D03*
X877500D03*
X887600Y811900D03*
X891200Y838200D03*
X878673Y804527D03*
X874569Y811300D03*
X885882Y861618D03*
X894965Y843500D03*
X877673Y868873D03*
X888962Y843262D03*
X873647Y861653D03*
X882333Y896320D03*
X895616Y985932D03*
X863800Y1309876D03*
X872164Y1350464D03*
X873259Y1365805D03*
X872181Y1354764D03*
X886792Y1404100D03*
X873918Y1411149D03*
X873800Y1418200D03*
X871432Y1420932D03*
X874900Y1421900D03*
X877406Y1419124D03*
X875740Y1415070D03*
X882226Y1404197D03*
X873694Y1404575D03*
X873700Y1375746D03*
X873570Y1380401D03*
X872192Y1424492D03*
X882000Y1432600D03*
X870921Y1432300D03*
X888800Y1493500D03*
X876514Y1514948D03*
X863851Y1501681D03*
X877828Y1500379D03*
X892966Y1508549D03*
X893036Y1512600D03*
X877946Y1496527D03*
X876096Y1505499D03*
X889002Y1489638D03*
X873972Y1472467D03*
X873922Y1477766D03*
X860179Y1491170D03*
X893020Y1566530D03*
X876200Y1553900D03*
X892700Y1543900D03*
X892558Y1528458D03*
X889300Y1551000D03*
X876190Y1537187D03*
X876100Y1549000D03*
X876200Y1558400D03*
X892700Y1524700D03*
X848551Y1542440D03*
X922687Y93D03*
X928138Y-8453D03*
X942000Y752850D03*
X897000Y839000D03*
X903000Y842500D03*
X920810Y902210D03*
X928100Y900650D03*
X900615Y909723D03*
X902571Y906534D03*
X903368Y934568D03*
X904594Y931141D03*
X916204Y938572D03*
X917550Y934742D03*
X901540Y937712D03*
X896679Y927505D03*
X896420Y916712D03*
X898468Y912970D03*
X931085Y936172D03*
X941274Y900845D03*
X934142Y974344D03*
X939481Y980230D03*
X912994Y971921D03*
X910397Y979189D03*
X902991Y982230D03*
X909826Y982874D03*
X905271Y974586D03*
X899846Y971468D03*
X898617Y975434D03*
X895837Y978389D03*
X896629Y982285D03*
X935623Y971054D03*
X904601Y998556D03*
X910040Y1006613D03*
X911807Y1002342D03*
X919656Y998764D03*
X939544Y1003485D03*
X903442Y1003265D03*
X896371Y1002112D03*
X936378Y1035722D03*
X920770Y1067389D03*
X921149Y1062424D03*
X914948Y1063255D03*
X908477Y1061823D03*
X910387Y1055344D03*
X904875Y1051177D03*
X896500Y1341800D03*
X936959Y1360143D03*
X896212Y1345788D03*
X895900Y1390100D03*
X896200Y1386000D03*
X896100Y1393800D03*
X896200Y1397900D03*
Y1405300D03*
X896100Y1401600D03*
X923829Y1389012D03*
X936994Y1379895D03*
X927601Y1384433D03*
X923486Y1384268D03*
X906600Y1461600D03*
X909400Y1459200D03*
X910000Y1464900D03*
X905500Y1467161D03*
X938000Y1499200D03*
X942000Y1499500D03*
X922500Y1499700D03*
X908742Y1477427D03*
X908542Y1481127D03*
X922500Y1509700D03*
X941000Y1564200D03*
X937000D03*
X926500Y1556700D03*
X931500Y1564200D03*
X913250Y1547700D03*
X940000Y1529200D03*
X940750Y1549200D03*
X900000Y1526500D03*
X897400Y1574000D03*
X897038Y1577600D03*
X911516Y1573202D03*
X911616Y1576802D03*
X911710Y1582375D03*
X911094Y1585923D03*
X924059Y1647700D03*
X981700Y-115500D03*
X976713Y-115570D03*
X991713Y-115413D03*
X989316Y-94984D03*
X992185Y-54411D03*
X989050Y-70850D03*
X990565Y130230D03*
Y135230D03*
Y125230D03*
X985688Y362549D03*
X977794Y695103D03*
X952200Y742600D03*
X957100Y742900D03*
X977622Y699464D03*
X953200Y736700D03*
X956900Y737600D03*
X949048Y755225D03*
X952476Y753652D03*
X951300Y747900D03*
X956200Y748200D03*
X957320Y769818D03*
X947866Y763541D03*
X957629Y766231D03*
X952820Y769518D03*
X944500Y760750D03*
X961100Y931640D03*
X960503Y936185D03*
X967583Y933607D03*
X968698Y928957D03*
X974484Y935078D03*
X976419Y931628D03*
X976460Y927891D03*
X981679Y936678D03*
X976213Y938846D03*
X966000Y937500D03*
X953013Y960147D03*
X947174Y957150D03*
X979020Y960000D03*
Y956200D03*
X973900Y960000D03*
Y956200D03*
X968780Y960000D03*
Y956200D03*
X987734Y979575D03*
X951200Y1030700D03*
X946700D03*
X947759Y998726D03*
X961220Y1001600D03*
Y1005400D03*
X966340Y1001600D03*
Y1005400D03*
X971460Y1001600D03*
Y1005400D03*
X974020Y1026200D03*
Y1022400D03*
X968900Y1026200D03*
Y1022400D03*
X963780Y1026200D03*
Y1022400D03*
X956600Y1001700D03*
Y1005700D03*
X964537Y1160310D03*
X958870Y1163617D03*
X962941Y1165929D03*
X967497Y1168802D03*
X957871Y1171219D03*
X963000Y1174427D03*
X969463Y1177599D03*
X972924Y1158033D03*
X954395Y1145604D03*
X982387Y1183598D03*
X951525Y1369107D03*
X955500Y1369000D03*
X946300Y1499300D03*
X969198Y1505851D03*
X969472Y1501978D03*
X950300Y1499500D03*
X975813Y1556916D03*
X953500Y1563200D03*
X962000Y1564200D03*
X958000D03*
X949000D03*
X945000D03*
X972001Y1533926D03*
X975813Y1545916D03*
X954700Y1524100D03*
Y1530363D03*
X974787Y1525100D03*
Y1529300D03*
X948750Y1549200D03*
X979963Y1545689D03*
X1004213Y-95837D03*
X998045Y-79300D03*
X993816Y-95184D03*
X1036713Y-115500D03*
X1007582Y-39418D03*
X1000300Y-74200D03*
X1032080Y-45980D03*
X1004082Y-38200D03*
X1000418Y-69982D03*
X993000Y-60600D03*
X1019118Y-34382D03*
X1019082Y-71000D03*
X1026717Y-11646D03*
X1021086Y-11682D03*
X1010650Y49950D03*
Y67650D03*
X1030775Y130016D03*
X1030890Y137780D03*
X993565Y137730D03*
Y132730D03*
Y127730D03*
X1030774Y133840D03*
X1030758Y126274D03*
X1030825Y122335D03*
X1020250Y357188D03*
X1040180Y437510D03*
X1038215Y877191D03*
X1034271Y876911D03*
X1011100Y904600D03*
X1025000Y897700D03*
X1036431Y929752D03*
X1037083Y933300D03*
X1016842Y916445D03*
X1035947Y948800D03*
X1028657Y1009103D03*
X1020654Y1023940D03*
X1018094Y1021240D03*
X1015534Y1023840D03*
X1007849Y1033743D03*
X996600D03*
X1012974Y1021240D03*
X1013700Y1007640D03*
X1009509Y1009850D03*
X1037282Y995028D03*
X1005294Y997940D03*
Y1001740D03*
X1010414Y997940D03*
Y1001740D03*
X1023214Y1007140D03*
X1007372Y1023832D03*
X1017194Y1033840D03*
X1026900Y1129466D03*
X1022400Y1129183D03*
X1036160Y1095500D03*
Y1091700D03*
Y1111900D03*
X994923Y1137488D03*
X995948Y1184250D03*
X1017354Y1196124D03*
X1021061Y1198543D03*
X1016835Y1323916D03*
X1025335Y1324216D03*
X1016672Y1338228D03*
X1025284Y1341216D03*
X1025335Y1337616D03*
Y1330916D03*
X1016600Y1332000D03*
X1033000Y1416125D03*
X1028000Y1404700D03*
Y1411000D03*
X1031500Y1408000D03*
X1020854Y1455075D03*
X1016854D03*
X1051713Y-114887D03*
X1056713Y-115413D03*
X1086713Y-115570D03*
X1081713D03*
X1071713D03*
X1066713D03*
X1041713Y-115465D03*
X1085300Y-90700D03*
X1079455Y-30742D03*
X1043000Y-67600D03*
X1043112Y-34912D03*
X1066600Y-72800D03*
X1066225Y-40278D03*
X1054593Y-51122D03*
X1078900Y-45782D03*
X1085800Y-57100D03*
X1070918Y-73618D03*
X1043303Y-27685D03*
X1045873Y-24660D03*
X1043513Y-21696D03*
X1077505Y22405D03*
X1076418Y31082D03*
X1076944Y35182D03*
X1077260Y42612D03*
X1077400Y52000D03*
X1077082Y38982D03*
X1076905Y46195D03*
X1076299Y27282D03*
X1054800Y22405D03*
X1041500Y382858D03*
X1078100Y392600D03*
Y397600D03*
Y402600D03*
X1072600Y392500D03*
Y397500D03*
Y402500D03*
X1045292Y384688D03*
X1074425Y447225D03*
X1071950Y453288D03*
X1072600Y407500D03*
X1078100Y407600D03*
X1043674Y451921D03*
X1043500Y446600D03*
X1042800Y442000D03*
X1069018Y456900D03*
X1065985Y460500D03*
X1054419Y839493D03*
Y828081D03*
X1050763Y829163D03*
X1086600Y833200D03*
X1044101Y927130D03*
X1083633Y932172D03*
X1073408Y942399D03*
X1058571Y943852D03*
X1053099Y1021657D03*
X1048512Y1021378D03*
X1041616Y997225D03*
X1069000Y1067100D03*
X1083355Y1125903D03*
X1070155D03*
X1048960Y1113900D03*
Y1117700D03*
X1041280Y1121500D03*
Y1113900D03*
Y1117700D03*
X1081078Y1095362D03*
X1083660Y1092700D03*
X1041280Y1095500D03*
Y1091700D03*
Y1100500D03*
X1048960Y1095500D03*
Y1091700D03*
Y1099300D03*
X1054080Y1113900D03*
Y1117700D03*
X1068700Y1108700D03*
X1083355Y1116103D03*
X1070155D03*
X1075600Y1179090D03*
X1053743Y1174221D03*
X1046900Y1168000D03*
X1052522Y1145153D03*
X1076032Y1191144D03*
X1070000Y1184100D03*
X1079500Y1276100D03*
X1047000Y1258687D03*
X1051300Y1253300D03*
X1077300Y1271700D03*
X1042343Y1324216D03*
X1048251Y1349992D03*
X1046372Y1356326D03*
X1042343Y1337616D03*
X1042443Y1342668D03*
X1042343Y1330916D03*
X1076754Y1455075D03*
X1072754D03*
X1044654D03*
X1048654D03*
X1100929Y-90371D03*
X1116600Y-85538D03*
X1106300Y-94800D03*
X1089318Y-91682D03*
X1101246Y-31005D03*
X1124024Y-30840D03*
X1128765Y-34297D03*
X1094200Y-38400D03*
X1111254Y-31020D03*
X1105328Y-31005D03*
X1094300Y-60300D03*
X1103300Y-60000D03*
X1115603Y-60293D03*
X1134110Y176500D03*
X1136203Y167600D03*
X1089300Y836100D03*
X1119419Y888607D03*
X1116419Y896107D03*
Y891107D03*
X1119419Y893607D03*
Y898607D03*
X1110447Y944217D03*
X1105447D03*
X1100447D03*
X1102947Y947217D03*
X1107947D03*
X1091400Y1070900D03*
X1091494Y1075994D03*
X1097800Y1070700D03*
X1097500Y1075100D03*
X1103800Y1070600D03*
Y1075600D03*
X1128900Y1067200D03*
X1119500Y1125100D03*
X1115000D03*
X1123600Y1096400D03*
X1123838Y1092800D03*
X1123600Y1100000D03*
X1133981Y1096283D03*
X1134002Y1092600D03*
X1134103Y1099881D03*
X1137436Y1124750D03*
X1128800Y1125100D03*
X1092200Y1125800D03*
X1103064Y1113626D03*
X1099020Y1112276D03*
X1096460Y1115125D03*
X1092742Y1113462D03*
X1134100Y1433300D03*
X1146768Y-31238D03*
X1139808Y-31171D03*
X1149699Y-35153D03*
X1142293Y-37522D03*
X1181568Y55168D03*
X1181868Y50568D03*
Y45568D03*
X1181568Y60168D03*
X1178268Y64068D03*
X1183268D03*
X1178268Y85068D03*
Y69068D03*
Y89068D03*
X1183268Y85068D03*
Y69068D03*
Y89068D03*
X1178656Y104637D03*
X1176952Y93390D03*
X1140550Y179200D03*
X1142800Y174637D03*
X1140500Y171400D03*
X1171749Y259163D03*
X1175400Y258800D03*
X1176300Y284500D03*
X1180953Y284800D03*
X1185588Y285035D03*
X1185000Y281343D03*
X1176100Y270603D03*
X1176300Y288600D03*
X1169768Y730300D03*
Y723100D03*
Y726700D03*
X1175568Y712300D03*
X1171968D03*
X1175568Y715900D03*
X1171968D03*
X1173368Y730300D03*
X1171968Y719500D03*
X1175568D03*
X1173368Y726700D03*
Y723100D03*
X1138198Y832424D03*
X1172736Y1031786D03*
X1177036Y1032086D03*
X1170140Y1043939D03*
X1152880Y1097672D03*
X1152682Y1091138D03*
X1149984Y1115804D03*
X1143550Y1120317D03*
X1139524Y1121817D03*
X1152800Y1223062D03*
X1152700Y1216213D03*
X1150420Y1229800D03*
X1181400Y1266100D03*
X1184000Y1260100D03*
X1149823Y1233373D03*
X1144000Y1310000D03*
X1150232Y1316358D03*
X1154500Y1327500D03*
X1150911Y1329500D03*
X1147900Y1421500D03*
X1143900Y1431000D03*
X1142400Y1427700D03*
X1146002Y1427906D03*
X1145007Y1424446D03*
X1148556Y1425056D03*
X1188268Y64068D03*
Y85068D03*
Y69068D03*
Y89068D03*
X1215795Y181242D03*
X1215600Y261800D03*
X1219962Y244739D03*
X1186600Y253200D03*
X1215547Y246355D03*
X1194700Y261700D03*
X1189700Y308527D03*
X1190200Y285023D03*
X1201835Y305319D03*
X1193800Y307857D03*
X1198100Y306858D03*
X1194600Y288237D03*
X1197000Y279400D03*
X1226045Y431102D03*
X1194000Y1037900D03*
X1232842Y1140722D03*
X1198130Y1151410D03*
X1205303Y1227604D03*
X1250016Y247017D03*
X1253300Y227700D03*
X1262075Y297100D03*
X1250500Y266600D03*
X1239362Y524168D03*
X1253511Y517606D03*
X1264878Y508068D03*
X1268400Y716100D03*
X1265891Y699583D03*
X1263250Y823436D03*
X1243200Y933700D03*
X1259808Y927260D03*
X1271296Y986867D03*
X1274413Y984613D03*
X1279599Y976407D03*
X1253338Y980784D03*
X1253975Y970147D03*
X1264269Y981248D03*
X1263618Y990606D03*
X1268378Y990608D03*
X1239900Y1024000D03*
X1256142Y1029316D03*
X1252400Y1054100D03*
X1272755Y1137293D03*
X1260300Y1169000D03*
X1240314Y1139741D03*
X1268948Y1150173D03*
X1254800Y1269600D03*
X1240276Y1356700D03*
X1323829Y55929D03*
X1328295Y55800D03*
X1320055Y68000D03*
X1304563Y100771D03*
X1299569Y100639D03*
X1312263Y95463D03*
X1327921Y78900D03*
X1308228Y93399D03*
X1315961Y98112D03*
X1314794Y162944D03*
X1324134Y126967D03*
X1313127Y120839D03*
X1315118Y126967D03*
X1324207Y138756D03*
X1315102Y137903D03*
X1330807Y181473D03*
X1311750Y187911D03*
X1326637Y226568D03*
X1316637D03*
X1321637D03*
X1326500Y627917D03*
X1311750Y640667D03*
X1312000Y615417D03*
X1318000Y680417D03*
X1323000D03*
X1328000D03*
X1316000Y772200D03*
X1310500Y774700D03*
X1312767Y885535D03*
X1286000Y982200D03*
X1284695Y956586D03*
X1326500Y1080673D03*
X1317400Y1068000D03*
X1309600Y1068173D03*
X1311750Y1093423D03*
X1328000Y1133173D03*
X1318000D03*
X1323000D03*
X1351200Y68600D03*
X1359350Y66350D03*
X1358355Y81488D03*
X1338215Y107586D03*
X1336034Y82542D03*
X1334383Y75892D03*
X1340961Y78811D03*
X1343521Y85472D03*
X1347607Y101337D03*
X1346081Y80671D03*
X1348641Y83326D03*
X1352351Y101724D03*
X1350779Y106496D03*
X1348641Y110550D03*
X1333281Y85133D03*
X1341922Y105649D03*
X1354500Y75400D03*
X1349931Y138361D03*
X1338400Y126015D03*
X1333988Y161471D03*
X1358971Y129978D03*
X1362685Y130109D03*
X1351665Y128325D03*
X1343112Y128997D03*
X1364017Y123277D03*
X1337662Y137188D03*
X1334500Y202548D03*
Y207548D03*
Y212548D03*
Y217548D03*
X1372274Y272874D03*
X1355991Y275272D03*
X1374338Y292900D03*
X1358573Y290900D03*
X1375700Y413400D03*
X1357316Y542311D03*
X1346057Y529857D03*
X1338100Y520300D03*
X1353500Y518900D03*
X1359882Y508014D03*
X1364882D03*
X1336000Y627000D03*
X1334000Y666417D03*
Y661917D03*
Y657417D03*
Y652917D03*
X1373553Y700994D03*
X1347600Y734078D03*
X1344062Y737800D03*
X1354500Y747304D03*
X1360920Y749829D03*
X1334300Y771200D03*
X1338729Y776131D03*
X1338700Y771500D03*
X1334329Y775831D03*
X1373519Y761900D03*
X1341219Y933282D03*
X1346080Y907004D03*
X1378100Y972100D03*
X1339404Y969600D03*
X1353762Y969886D03*
X1367382Y961355D03*
X1362382D03*
X1349829Y1014840D03*
X1365551Y1028250D03*
X1361074Y1114565D03*
X1334500Y1104700D03*
Y1111173D03*
Y1116173D03*
Y1121173D03*
X1360238Y1143867D03*
X1370716Y1148037D03*
X1351321Y1152553D03*
X1355733Y1241900D03*
X1369600Y1330100D03*
X1373700Y1330000D03*
X1365551Y1353500D03*
X1427663Y167032D03*
X1384475Y255839D03*
X1384713Y323200D03*
X1414882Y397271D03*
X1395300Y438500D03*
X1418225Y421700D03*
X1418493Y531407D03*
X1425600Y544600D03*
X1418507Y517007D03*
X1407936Y552099D03*
Y548099D03*
X1425200Y540100D03*
X1414319Y523900D03*
X1396297Y573397D03*
X1421239Y558029D03*
X1396297Y579803D03*
X1421239Y562229D03*
X1383952Y717435D03*
X1392355Y886696D03*
X1391000Y932400D03*
X1380300Y930200D03*
X1384800Y1002666D03*
X1383899Y1166690D03*
X1388500Y1224900D03*
X1381800Y1329600D03*
X1463804Y138605D03*
X1436204Y159247D03*
X1435963Y183833D03*
X1450713Y173049D03*
X1456373Y168971D03*
X1458764Y212625D03*
Y208025D03*
Y203425D03*
X1442213Y227661D03*
X1447213D03*
X1452213D03*
X1458764Y217225D03*
X1444238Y349852D03*
X1439654D03*
X1431909Y359311D03*
X1463000Y490638D03*
X1457200Y549600D03*
X1470700Y522100D03*
X1456439Y515000D03*
X1448261D03*
X1435200D03*
X1443700D03*
X1460200D03*
X1452200D03*
X1465700D03*
X1439200D03*
X1442500Y548400D03*
X1456450Y529600D03*
X1448450D03*
X1459200Y579600D03*
X1452200D03*
X1442500Y554700D03*
X1455750Y572350D03*
X1474700Y569100D03*
X1447700Y579600D03*
X1474700Y579100D03*
X1450713Y627817D03*
X1435963Y640667D03*
X1455202Y618557D03*
X1436213Y615417D03*
X1442213Y680417D03*
X1447213D03*
X1452213D03*
X1458713Y658417D03*
Y663417D03*
Y668417D03*
Y652217D03*
X1474083Y764750D03*
X1471608Y768500D03*
X1435300Y882700D03*
X1440500Y893500D03*
X1448000Y910000D03*
X1463616Y969265D03*
X1451800Y1004700D03*
X1450713Y1080673D03*
X1446213Y1062300D03*
X1436213Y1068173D03*
X1442213Y1132173D03*
X1447213D03*
X1452213D03*
X1439750Y1096673D03*
X1461713Y1123173D03*
Y1118173D03*
Y1113173D03*
X1461700Y1107200D03*
X1470953Y1152427D03*
X1475953D03*
X1467000Y1221800D03*
X1473600Y1242777D03*
X1511177Y125412D03*
X1499775Y248061D03*
X1508925Y323200D03*
X1481938Y489926D03*
X1485932Y522335D03*
X1500600Y523300D03*
X1502400Y544100D03*
X1497849Y545264D03*
X1486594Y508098D03*
X1491594D03*
X1513200Y519700D03*
X1509800Y516100D03*
X1494400Y560400D03*
Y556100D03*
X1500539Y739639D03*
X1498000Y743000D03*
X1505900Y717600D03*
X1495480Y704558D03*
X1489000Y723000D03*
X1476558Y759088D03*
X1479033Y762259D03*
X1486600Y786559D03*
X1505900Y930400D03*
X1521200Y928000D03*
X1503394Y968179D03*
X1477974Y970044D03*
X1491594Y961355D03*
X1486594D03*
X1484000Y992315D03*
X1481500Y995758D03*
X1478194Y1017166D03*
X1481529Y1030500D03*
X1485608Y1113628D03*
X1504200Y1171300D03*
X1485833Y1140369D03*
X1495900Y1149000D03*
X1491662Y1351300D03*
X1494662Y1336000D03*
X1497200Y1342500D03*
X1501600Y1342300D03*
X1560425Y162661D03*
X1560175Y187911D03*
X1566425Y227661D03*
X1571425D03*
X1568500Y438500D03*
Y544100D03*
X1568000Y548500D03*
X1555175Y642667D03*
X1560425Y615417D03*
X1566425Y677417D03*
X1571425D03*
X1565593Y654856D03*
X1565618Y660773D03*
Y665773D03*
Y670773D03*
X1526000Y728000D03*
X1570500Y888400D03*
X1570425Y1062000D03*
X1560425Y1068173D03*
X1547800Y1098819D03*
X1552800D03*
X1557800D03*
X1562800D03*
X1556231Y1134920D03*
X1558650Y1217426D03*
X1574925Y175061D03*
X1579371Y166019D03*
X1582925Y210661D03*
Y205661D03*
Y200661D03*
X1576425Y227661D03*
X1621100Y244661D03*
X1582925Y215661D03*
X1586596Y518723D03*
X1600745Y517561D03*
X1615807Y508600D03*
X1610807D03*
X1574925Y627817D03*
X1578926Y618657D03*
X1576425Y677417D03*
X1620469Y697517D03*
X1584800Y895800D03*
X1587400Y912200D03*
X1608200Y914400D03*
X1618200Y916800D03*
X1574576Y976700D03*
X1615494Y973179D03*
X1587829Y969191D03*
X1602187Y969970D03*
X1615807Y961355D03*
X1610807D03*
X1580381Y1007066D03*
X1602400Y1019366D03*
X1620059Y1032932D03*
X1574925Y1080673D03*
X1603425Y1105040D03*
Y1100040D03*
X1598425Y1102440D03*
Y1107440D03*
X1620059Y1128071D03*
X1615909Y1150262D03*
X1613400Y1236500D03*
X1622738Y264938D03*
X1621138Y719238D03*
X1643344Y887455D03*
X1646013Y884255D03*
X1639644Y889755D03*
X1633600Y936300D03*
X1621787Y917108D03*
X1636400Y925800D03*
X1629094Y975179D03*
X1624198Y1111309D03*
X1633138Y1165673D03*
X1635688Y1153773D03*
X1624500Y1349100D03*
X1684638Y162661D03*
X1684388Y187911D03*
X1699138Y175061D03*
X1703584Y166019D03*
X1707138Y210661D03*
Y205661D03*
Y200661D03*
X1690638Y227661D03*
X1695638D03*
X1700638D03*
X1707138Y215661D03*
X1711061Y518470D03*
X1684388Y638324D03*
X1699138Y627917D03*
X1705000Y618667D03*
X1684638Y615417D03*
X1699638Y675417D03*
X1689638D03*
X1694638D03*
X1707100Y652500D03*
X1707138Y658417D03*
Y663417D03*
Y668417D03*
X1692100Y923600D03*
X1704010Y898000D03*
X1674814Y961977D03*
X1677056Y954636D03*
X1680012Y952402D03*
X1685047Y1014966D03*
X1680087Y1023983D03*
X1671422Y1009266D03*
X1690279Y1011526D03*
X1691771Y1035163D03*
X1699138Y1080573D03*
X1685100Y1054000D03*
X1679300Y1043169D03*
X1694638Y1063600D03*
X1684638Y1068173D03*
X1700638Y1131673D03*
X1695638D03*
X1690638D03*
X1684388Y1091723D03*
X1707138Y1111173D03*
Y1116173D03*
Y1121173D03*
X1707200Y1105200D03*
X1702838Y1215300D03*
X1710617Y1231429D03*
X1715049Y1234000D03*
X1746400Y244561D03*
X1747550Y265000D03*
X1725100Y519300D03*
X1740019Y508600D03*
X1735019D03*
X1752000Y929200D03*
X1755010Y966285D03*
X1740019Y961355D03*
X1735019D03*
X1738863Y985225D03*
X1755900Y1014600D03*
X1740499Y1008223D03*
X1749863Y1003925D03*
X1756100Y1004362D03*
X1746030Y1004209D03*
X1737241Y997843D03*
X1740363Y989225D03*
X1733245Y1115503D03*
X1751400Y1173900D03*
X1732768Y1141697D03*
X1748100Y1153673D03*
X1718117Y1152553D03*
X1723117D03*
X1755900Y1212704D03*
X1740000Y1346900D03*
X1808850Y162661D03*
X1808600Y187911D03*
Y640667D03*
X1808850Y615417D03*
X1766721Y720500D03*
X1813851Y927406D03*
X1768692Y966073D03*
X1797463Y968652D03*
X1806077Y961860D03*
X1782666Y961344D03*
X1777666D03*
X1783778Y970371D03*
X1774863Y1024725D03*
X1788726Y1034726D03*
X1778863Y1005725D03*
X1787163Y1009741D03*
X1772863Y1005304D03*
X1778963Y999125D03*
X1772263Y995925D03*
X1812050Y1071223D03*
X1805250Y1067973D03*
X1841021Y152968D03*
X1845517Y158475D03*
X1856219Y201661D03*
X1823350Y175161D03*
X1827796Y166019D03*
X1831350Y210661D03*
Y205661D03*
Y200661D03*
X1850669Y219661D03*
X1846169D03*
X1841669D03*
X1824850Y227661D03*
X1819850D03*
X1814850D03*
X1831350Y215661D03*
X1834896Y518597D03*
X1849045Y517435D03*
X1859232Y508600D03*
X1823350Y627917D03*
X1827667Y618703D03*
X1840855Y606200D03*
X1845417Y611231D03*
X1841669Y672417D03*
X1846169D03*
X1850669D03*
X1814850Y680417D03*
X1819850D03*
X1824850D03*
X1856219Y654417D03*
X1831350Y658417D03*
Y663417D03*
Y668417D03*
X1831300Y652600D03*
X1855676Y800787D03*
X1824170Y886349D03*
X1819541Y921500D03*
X1823937Y890883D03*
X1821152Y907899D03*
X1823350Y1080673D03*
X1858046Y1092779D03*
X1836953Y1103391D03*
X1850363Y1115037D03*
X1847506Y1118794D03*
X1851565Y1118784D03*
X1850280Y1111373D03*
X1816046Y1098532D03*
X1836200Y1130000D03*
X1828850Y1106173D03*
Y1111173D03*
Y1116173D03*
Y1121173D03*
X1824850Y1133173D03*
X1814850D03*
X1819850D03*
X1840585Y1151653D03*
X1836400Y1151900D03*
X1842000Y1344700D03*
X1869500Y179134D03*
X1876938Y181062D03*
X1865669Y201661D03*
X1870669D03*
X1875669D03*
X1880669D03*
X1864232Y508600D03*
X1869500Y633500D03*
X1878900Y637000D03*
X1879669Y652917D03*
X1874669D03*
X1869669D03*
X1864669D03*
X1884800Y890750D03*
X1902441Y888500D03*
X1896943Y894350D03*
X1891676Y917759D03*
X1884500Y912500D03*
X1904000Y933500D03*
Y929000D03*
Y925000D03*
X1906500Y893400D03*
X1909358Y897500D03*
X1904000Y938000D03*
X1873001Y901396D03*
X1904000Y921000D03*
X1872190Y936766D03*
X1867963Y996425D03*
X1887402Y1050193D03*
X1872162Y1055426D03*
X1864617Y1040934D03*
X1888085Y1059938D03*
X1876662Y1055426D03*
X1864833Y1091419D03*
X1870779Y1091763D03*
X1875779D03*
X1880779D03*
X1873500Y1329000D03*
X1911676Y893469D03*
G54D33*
X429724Y116339D03*
Y96654D03*
Y102166D03*
Y110827D03*
X443898Y116339D03*
X458071D03*
X436811Y114764D03*
X450984D03*
X443898Y96654D03*
X458071D03*
X443898Y102166D03*
X458071D03*
X436811Y100591D03*
X450984D03*
X436811Y106103D03*
X450984D03*
X443898Y110827D03*
X458071D03*
X436811Y120276D03*
X450984D03*
X465157Y114764D03*
X472244Y116339D03*
X479331Y114764D03*
X465157Y100591D03*
Y106103D03*
X472244Y96654D03*
Y102166D03*
X479331Y100591D03*
Y106103D03*
X472244Y110827D03*
X465157Y120276D03*
X479331D03*
X514764Y116339D03*
Y110827D03*
Y102166D03*
Y96654D03*
X550197Y114764D03*
X536024D03*
X521850D03*
X543110Y116339D03*
X528937D03*
X543110Y110827D03*
X528937D03*
X550197Y106103D03*
X536024D03*
X521850D03*
X550197Y100591D03*
X536024D03*
X521850D03*
X543110Y102166D03*
X528937D03*
X543110Y96654D03*
X528937D03*
X557283Y116339D03*
Y110827D03*
Y102166D03*
Y96654D03*
X550197Y120276D03*
X536024D03*
X521850D03*
X564370Y114764D03*
Y106103D03*
Y100591D03*
Y120276D03*
X833859Y1598425D03*
Y1603937D03*
Y1612599D03*
X840945Y1602363D03*
X826772D03*
X840945Y1607874D03*
X826772D03*
X840945Y1616536D03*
X826772D03*
X833859Y1618111D03*
Y1626772D03*
Y1632284D03*
Y1640945D03*
Y1646457D03*
X840945Y1622048D03*
X826772D03*
X840945Y1630709D03*
X826772D03*
X840945Y1636221D03*
X826772D03*
X840945Y1644882D03*
X826772D03*
X840945Y1650394D03*
X826772D03*
X876378Y1598425D03*
X862205D03*
X848032D03*
X876378Y1603937D03*
X862205D03*
X848032D03*
X876378Y1612599D03*
X862205D03*
X848032D03*
X890552Y1602363D03*
X869292D03*
X855118D03*
X890552Y1607874D03*
X869292D03*
X855118D03*
X890552Y1612205D03*
Y1616536D03*
X869292D03*
X855118D03*
X876378Y1618111D03*
X862205D03*
X848032D03*
X876378Y1626772D03*
X862205D03*
X848032D03*
X876378Y1632284D03*
X862205D03*
X848032D03*
X876378Y1640945D03*
X862205D03*
X848032D03*
X876378Y1646457D03*
X862205D03*
X848032D03*
X890552Y1622048D03*
X869292D03*
X855118D03*
X890552Y1626378D03*
Y1630709D03*
X869292D03*
X855118D03*
X890552Y1636221D03*
X869292D03*
X855118D03*
X890552Y1640551D03*
Y1644882D03*
X869292D03*
X855118D03*
X890552Y1650394D03*
X869292D03*
X855118D03*
X911811Y1603937D03*
Y1608268D03*
Y1612599D03*
X904725Y1602363D03*
Y1607874D03*
Y1612205D03*
Y1616536D03*
X911811Y1594095D03*
Y1598425D03*
X904725Y1598032D03*
X897638Y1598425D03*
Y1603937D03*
Y1608268D03*
Y1612599D03*
X911811Y1632284D03*
Y1636614D03*
Y1640945D03*
Y1646457D03*
Y1650788D03*
X904725Y1630709D03*
Y1636221D03*
Y1640551D03*
Y1644882D03*
Y1650394D03*
X911811Y1618111D03*
Y1622441D03*
Y1626772D03*
X904725Y1622048D03*
Y1626378D03*
X897638Y1618111D03*
Y1622441D03*
Y1626772D03*
Y1632284D03*
Y1636614D03*
Y1640945D03*
Y1646457D03*
Y1650788D03*
X1095420Y988592D03*
X1100932D03*
X1109593D03*
X1115105D03*
X1123766D03*
X1129278D03*
X1099357Y995678D03*
X1104869D03*
X1113530D03*
X1119042D03*
X1127703D03*
X1133215D03*
X1095420Y1002765D03*
X1100932D03*
X1109593D03*
X1115105D03*
X1123766D03*
X1129278D03*
X1099357Y1009852D03*
X1104869D03*
X1113530D03*
X1119042D03*
X1127703D03*
X1133215D03*
X1095420Y1016938D03*
X1100932D03*
X1109593D03*
X1115105D03*
X1123766D03*
X1129278D03*
X1099357Y1024025D03*
X1104869D03*
X1113530D03*
X1119042D03*
X1127703D03*
X1133215D03*
X1095420Y1031111D03*
X1100932D03*
X1109593D03*
X1115105D03*
X1123766D03*
X1129278D03*
X1099357Y1038198D03*
X1104869D03*
X1113530D03*
X1119042D03*
X1127703D03*
X1133215D03*
X1095420Y1160257D03*
Y1174430D03*
X1100932Y1160257D03*
Y1174430D03*
X1109593Y1160257D03*
Y1174430D03*
X1115105Y1160257D03*
Y1174430D03*
X1123766Y1160257D03*
Y1174430D03*
X1129278Y1160257D03*
Y1174430D03*
X1099357Y1167343D03*
X1104869D03*
X1113530D03*
X1119042D03*
X1127703D03*
X1133215D03*
X1095420Y1188603D03*
Y1202776D03*
Y1216949D03*
X1100932Y1188603D03*
Y1202776D03*
Y1216949D03*
X1109593Y1188603D03*
Y1202776D03*
Y1216949D03*
X1115105Y1188603D03*
Y1202776D03*
Y1216949D03*
X1123766Y1188603D03*
Y1202776D03*
Y1216949D03*
X1129278Y1188603D03*
Y1202776D03*
Y1216949D03*
X1099357Y1181516D03*
Y1195690D03*
Y1209863D03*
Y1224036D03*
X1104869Y1181516D03*
Y1195690D03*
Y1209863D03*
Y1224036D03*
X1113530Y1181516D03*
Y1195690D03*
Y1209863D03*
Y1224036D03*
X1119042Y1181516D03*
Y1195690D03*
Y1209863D03*
Y1224036D03*
X1127703Y1181516D03*
Y1195690D03*
Y1209863D03*
Y1224036D03*
X1133215Y1181516D03*
Y1195690D03*
Y1209863D03*
Y1224036D03*
X1095420Y1231123D03*
Y1245296D03*
Y1259469D03*
Y1273642D03*
X1100932Y1231123D03*
Y1245296D03*
Y1259469D03*
Y1273642D03*
X1109593Y1231123D03*
Y1245296D03*
Y1259469D03*
Y1273642D03*
X1115105Y1231123D03*
Y1245296D03*
Y1259469D03*
Y1273642D03*
X1123766Y1231123D03*
Y1245296D03*
Y1259469D03*
Y1273642D03*
X1129278Y1231123D03*
Y1245296D03*
Y1259469D03*
Y1273642D03*
X1099357Y1238209D03*
Y1252382D03*
Y1266556D03*
X1104869Y1238209D03*
Y1252382D03*
Y1266556D03*
X1113530Y1238209D03*
Y1252382D03*
Y1266556D03*
X1119042Y1238209D03*
Y1252382D03*
Y1266556D03*
X1127703Y1238209D03*
Y1252382D03*
Y1266556D03*
X1133215Y1238209D03*
Y1252382D03*
Y1266556D03*
X1095420Y1287816D03*
Y1301989D03*
Y1316162D03*
X1100932Y1287816D03*
Y1301989D03*
Y1316162D03*
X1109593Y1287816D03*
Y1301989D03*
Y1316162D03*
X1115105Y1287816D03*
Y1301989D03*
Y1316162D03*
X1123766Y1287816D03*
Y1301989D03*
Y1316162D03*
X1129278Y1287816D03*
Y1301989D03*
Y1316162D03*
X1099357Y1280729D03*
Y1294902D03*
Y1309075D03*
Y1323249D03*
X1104869Y1280729D03*
Y1294902D03*
Y1309075D03*
Y1323249D03*
X1113530Y1280729D03*
Y1294902D03*
Y1309075D03*
Y1323249D03*
X1119042Y1280729D03*
Y1294902D03*
Y1309075D03*
Y1323249D03*
X1127703Y1280729D03*
Y1294902D03*
Y1309075D03*
Y1323249D03*
X1133215Y1280729D03*
Y1294902D03*
Y1309075D03*
Y1323249D03*
X1095420Y1330335D03*
Y1344508D03*
Y1358682D03*
Y1372855D03*
X1100932Y1330335D03*
Y1344508D03*
Y1358682D03*
Y1372855D03*
X1109593Y1330335D03*
Y1344508D03*
Y1358682D03*
Y1372855D03*
X1115105Y1330335D03*
Y1344508D03*
Y1358682D03*
Y1372855D03*
X1123766Y1330335D03*
Y1344508D03*
Y1358682D03*
Y1372855D03*
X1129278Y1330335D03*
Y1344508D03*
Y1358682D03*
Y1372855D03*
X1099357Y1337422D03*
Y1351595D03*
Y1365768D03*
X1104869Y1337422D03*
Y1351595D03*
Y1365768D03*
X1113530Y1337422D03*
Y1351595D03*
Y1365768D03*
X1119042Y1337422D03*
Y1351595D03*
Y1365768D03*
X1127703Y1337422D03*
Y1351595D03*
Y1365768D03*
X1133215Y1337422D03*
Y1351595D03*
Y1365768D03*
X1095420Y1387028D03*
Y1401201D03*
X1100932Y1387028D03*
Y1401201D03*
X1109593Y1387028D03*
Y1401201D03*
X1115105Y1387028D03*
Y1401201D03*
X1123766Y1387028D03*
Y1401201D03*
X1129278Y1387028D03*
Y1401201D03*
X1099357Y1379942D03*
Y1394115D03*
Y1408288D03*
X1104869Y1379942D03*
Y1394115D03*
Y1408288D03*
X1113530Y1379942D03*
Y1394115D03*
Y1408288D03*
X1119042Y1379942D03*
Y1394115D03*
Y1408288D03*
X1127703Y1379942D03*
Y1394115D03*
Y1408288D03*
X1133215Y1379942D03*
Y1394115D03*
Y1408288D03*
X1398228Y116339D03*
Y96654D03*
Y102166D03*
Y110827D03*
X1412402Y116339D03*
X1426575D03*
X1405315Y114764D03*
X1419488D03*
X1412402Y96654D03*
X1426575D03*
X1412402Y102166D03*
X1426575D03*
X1405315Y100591D03*
X1419488D03*
X1405315Y106103D03*
X1419488D03*
X1412402Y110827D03*
X1426575D03*
X1405315Y120276D03*
X1419488D03*
X1433661Y114764D03*
X1440748Y116339D03*
X1447835Y114764D03*
X1433661Y100591D03*
Y106103D03*
X1440748Y96654D03*
Y102166D03*
X1447835Y100591D03*
Y106103D03*
X1440748Y110827D03*
X1433661Y120276D03*
X1447835D03*
X1483268Y116339D03*
Y110827D03*
Y102166D03*
Y96654D03*
X1518701Y114764D03*
X1504528D03*
X1490354D03*
X1511614Y116339D03*
X1497441D03*
X1511614Y110827D03*
X1497441D03*
X1518701Y106103D03*
X1504528D03*
X1490354D03*
X1518701Y100591D03*
X1504528D03*
X1490354D03*
X1511614Y102166D03*
X1497441D03*
X1511614Y96654D03*
X1497441D03*
X1518701Y120276D03*
X1504528D03*
X1490354D03*
X1532874Y114764D03*
X1525787Y116339D03*
Y110827D03*
X1532874Y106103D03*
Y100591D03*
X1525787Y102166D03*
Y96654D03*
X1532874Y120276D03*
G54D42*
X988795Y1571058D03*
Y1576658D03*
X1026106Y1545595D03*
Y1539995D03*
X1031706Y1545595D03*
Y1539995D03*
X1020574Y1540059D03*
Y1545659D03*
X1039758Y1559605D03*
X1014974Y1540059D03*
Y1545659D03*
X1039358Y1565405D03*
X1033717Y1563634D03*
X1028223Y1563763D03*
X1022623D03*
X994305Y1566342D03*
X1017023Y1563763D03*
X1011476Y1565175D03*
X1005658Y1565005D03*
X1000058D03*
X1039958Y1553705D03*
Y1548105D03*
Y1542505D03*
X1039358Y1571005D03*
Y1576605D03*
X1005658Y1575905D03*
X1033917Y1574834D03*
X1033717Y1569234D03*
X1000058Y1575905D03*
X1028423Y1574963D03*
X1028223Y1569363D03*
X994460Y1577240D03*
X1022823Y1574963D03*
X1022623Y1569363D03*
X1017223Y1574963D03*
X1017023Y1569363D03*
X994305Y1571942D03*
X1011676Y1576375D03*
X1011476Y1570775D03*
X1005658Y1570605D03*
X1000058D03*
X1078358Y1561105D03*
Y1566705D03*
X1072758Y1561105D03*
Y1566705D03*
X1067158Y1561105D03*
Y1566705D03*
X1061558Y1561105D03*
Y1566705D03*
X1055768Y1566675D03*
X1055418Y1560785D03*
X1055618Y1554885D03*
Y1549285D03*
Y1543685D03*
X1078358Y1572305D03*
X1072758D03*
X1067158D03*
X1061558D03*
X1055768Y1572275D03*
Y1577875D03*
G54D20*
X111024Y302303D03*
Y755059D03*
Y1207815D03*
X235236Y302303D03*
Y755059D03*
Y1207815D03*
X359449Y302303D03*
Y755059D03*
Y1207815D03*
X483661Y302303D03*
Y755059D03*
Y1207815D03*
X607874Y302303D03*
Y755059D03*
Y1207815D03*
X732087Y302303D03*
Y755059D03*
Y1207815D03*
X1098524Y-115157D03*
X1281693Y302303D03*
Y755059D03*
Y1207815D03*
X1405906Y302303D03*
Y755059D03*
Y1207815D03*
X1530118Y302303D03*
Y755059D03*
Y1207815D03*
X1654331Y302303D03*
Y755059D03*
Y1207815D03*
X1778543Y302303D03*
Y755059D03*
Y1207815D03*
X1902756Y302303D03*
Y755059D03*
Y1207815D03*
G54D22*
X119763Y550725D03*
Y546225D03*
Y555225D03*
X124263Y546225D03*
Y550725D03*
Y555225D03*
X141978Y958572D03*
X142006Y978425D03*
X209863Y566625D03*
X199102Y969717D03*
Y974717D03*
X183584Y974789D03*
Y969789D03*
X199392Y985113D03*
X183551Y984789D03*
X212063Y976725D03*
X203063D03*
X207563D03*
X216563D03*
X212063Y981725D03*
X216563D03*
X207563D03*
X203063D03*
X199392Y990113D03*
X183551Y989789D03*
X250650Y556997D03*
Y561997D03*
X265545Y556794D03*
Y561794D03*
X250661Y572936D03*
Y577936D03*
X265590Y572801D03*
Y577801D03*
X225563Y976725D03*
X221063D03*
X225563Y981725D03*
X221063D03*
X269763Y569725D03*
X287763D03*
X292263D03*
X274263D03*
X283263D03*
X278763D03*
X283263Y564725D03*
X287763D03*
X292263D03*
X274263D03*
X269763D03*
X278763D03*
X637592Y593186D03*
X641792D03*
Y597386D03*
X637592D03*
X633392Y593186D03*
Y597386D03*
X629192Y593186D03*
Y597386D03*
X641792Y605786D03*
Y601586D03*
X637592D03*
Y605786D03*
X633392D03*
Y601586D03*
X629192D03*
Y605786D03*
X675913Y586555D03*
Y592955D03*
Y598155D03*
X672082Y582834D03*
X666882D03*
X661682D03*
X656482D03*
X695413Y600755D03*
X699613D03*
X669482Y613934D03*
Y609734D03*
X665282D03*
Y613934D03*
X661082D03*
Y609734D03*
X656882Y613934D03*
Y609734D03*
X675913Y603355D03*
X695413Y604955D03*
X691213Y613355D03*
X695413D03*
X699613D03*
X691213Y609155D03*
X695413D03*
X699613Y604955D03*
Y609155D03*
X703813Y592355D03*
Y596555D03*
Y600755D03*
Y613355D03*
Y609155D03*
Y604955D03*
X1370200Y550500D03*
X1366000D03*
X1378100Y530200D03*
Y534400D03*
X1365500Y538600D03*
X1369700D03*
X1365500Y534400D03*
X1369700D03*
X1373900D03*
X1365500Y530200D03*
X1369700D03*
X1373900D03*
X1375900Y568500D03*
X1366000Y563100D03*
X1370200D03*
Y554700D03*
X1366000D03*
X1370200Y558900D03*
X1366000D03*
X1373700Y582900D03*
X1369500D03*
X1377900Y587100D03*
Y591300D03*
Y595500D03*
X1373700D03*
Y591300D03*
Y587100D03*
X1369500Y595500D03*
Y591300D03*
Y587100D03*
X1377900Y599700D03*
X1373700D03*
X1369500D03*
X1396500Y549500D03*
X1386500Y534400D03*
Y530200D03*
X1382300D03*
Y534400D03*
X1396500Y559900D03*
Y554700D03*
Y565100D03*
X1393000Y568500D03*
X1387300D03*
X1381600D03*
X1382100Y587100D03*
X1386300D03*
X1434441Y590424D03*
X1434581Y586136D03*
X1697261Y1004347D03*
X1692761D03*
Y999847D03*
Y995347D03*
X1697261D03*
Y999847D03*
X1783806Y989468D03*
X1862652Y846508D03*
X1850263Y964540D03*
X1850370Y960239D03*
X1845870D03*
X1845763Y964540D03*
Y956040D03*
X1850263D03*
X1825741Y969210D03*
Y974210D03*
X1840683Y969318D03*
Y974318D03*
X1825744Y986011D03*
X1840578Y985885D03*
X1844863Y983125D03*
X1853863D03*
X1858363D03*
X1849363D03*
X1862863D03*
X1853863Y978125D03*
X1844863D03*
X1849363D03*
X1862863D03*
X1858363D03*
X1825744Y991011D03*
X1840578Y990885D03*
X1873099Y817150D03*
X1878099D03*
X1873099Y821650D03*
X1878099D03*
X1873099Y826150D03*
X1878099D03*
X1877512Y831377D03*
X1882512D03*
X1865202Y831559D03*
X1873012Y831377D03*
X1878099Y812650D03*
X1873099D03*
X1878099Y808150D03*
X1873099D03*
X1878099Y803650D03*
X1873099D03*
X1878373Y846472D03*
X1883373D03*
X1867652Y846508D03*
X1867363Y983125D03*
Y978125D03*
G54D19*
X111024Y153681D03*
Y606437D03*
Y1059193D03*
X235236Y153681D03*
Y606437D03*
Y1059193D03*
X359449Y153681D03*
Y606437D03*
Y1059193D03*
X483661Y153681D03*
Y606437D03*
Y1059193D03*
X607874Y153681D03*
Y606437D03*
Y1059193D03*
X732087Y153681D03*
Y606437D03*
Y1059193D03*
X949902Y-115157D03*
X1281693Y153681D03*
Y606437D03*
Y1059193D03*
X1405906Y153681D03*
Y606437D03*
Y1059193D03*
X1530118Y153681D03*
Y606437D03*
Y1059193D03*
X1654331Y153681D03*
Y606437D03*
Y1059193D03*
X1778543Y153681D03*
Y606437D03*
Y1059193D03*
X1902756Y153681D03*
Y606437D03*
Y1059193D03*
G54D32*
X429724Y68307D03*
X458071D03*
X443898D03*
X429724Y87993D03*
Y82481D03*
Y73819D03*
X458071Y87993D03*
Y82481D03*
X450984Y91930D03*
Y86418D03*
X443898Y87993D03*
Y82481D03*
X436811Y91930D03*
Y86418D03*
X458071Y73819D03*
X450984Y77756D03*
Y72245D03*
X443898Y73819D03*
X436811Y77756D03*
Y72245D03*
X472244Y68307D03*
X479331Y91930D03*
Y86418D03*
X472244Y87993D03*
Y82481D03*
X465157Y91930D03*
Y86418D03*
X479331Y77756D03*
Y72245D03*
X472244Y73819D03*
X465157Y77756D03*
Y72245D03*
X514764Y68307D03*
X543110D03*
X528937D03*
X557283D03*
X514764Y87993D03*
Y82481D03*
Y73819D03*
X550197Y91930D03*
Y86418D03*
X543110Y87993D03*
Y82481D03*
X536024Y91930D03*
Y86418D03*
X528937Y87993D03*
Y82481D03*
X521850Y91930D03*
Y86418D03*
X550197Y77756D03*
Y72245D03*
X543110Y73819D03*
X536024Y77756D03*
Y72245D03*
X528937Y73819D03*
X521850Y77756D03*
Y72245D03*
X557283Y87993D03*
Y82481D03*
Y73819D03*
X564370Y91930D03*
Y86418D03*
Y77756D03*
Y72245D03*
X1398228Y68307D03*
X1426575D03*
X1412402D03*
X1398228Y87993D03*
Y82481D03*
Y73819D03*
X1426575Y87993D03*
Y82481D03*
X1419488Y91930D03*
Y86418D03*
X1412402Y87993D03*
Y82481D03*
X1405315Y91930D03*
Y86418D03*
X1426575Y73819D03*
X1419488Y77756D03*
Y72245D03*
X1412402Y73819D03*
X1405315Y77756D03*
Y72245D03*
X1440748Y68307D03*
X1447835Y91930D03*
Y86418D03*
X1440748Y87993D03*
Y82481D03*
X1433661Y91930D03*
Y86418D03*
X1447835Y77756D03*
Y72245D03*
X1440748Y73819D03*
X1433661Y77756D03*
Y72245D03*
X1483268Y68307D03*
X1511614D03*
X1497441D03*
X1483268Y87993D03*
Y82481D03*
Y73819D03*
X1518701Y91930D03*
Y86418D03*
X1511614Y87993D03*
Y82481D03*
X1504528Y91930D03*
Y86418D03*
X1497441Y87993D03*
Y82481D03*
X1490354Y91930D03*
Y86418D03*
X1518701Y77756D03*
Y72245D03*
X1511614Y73819D03*
X1504528Y77756D03*
Y72245D03*
X1497441Y73819D03*
X1490354Y77756D03*
Y72245D03*
X1525787Y68307D03*
X1532874Y91930D03*
Y86418D03*
X1525787Y87993D03*
Y82481D03*
X1532874Y77756D03*
Y72245D03*
X1525787Y73819D03*
G54D38*
X929331Y16536D03*
X937205Y20473D03*
Y12599D03*
Y67717D03*
X929331Y48032D03*
Y32284D03*
X937205Y44095D03*
Y36221D03*
Y28347D03*
X929331Y103150D03*
Y87402D03*
Y71654D03*
X937205Y114961D03*
Y99213D03*
Y83465D03*
X929331Y166142D03*
Y150394D03*
Y134646D03*
Y118898D03*
X937205Y162205D03*
Y146457D03*
Y130709D03*
X929331Y213386D03*
Y197638D03*
Y181890D03*
X937205Y209449D03*
Y193701D03*
Y177953D03*
X929331Y260630D03*
Y244882D03*
Y229134D03*
X937205Y256693D03*
Y240945D03*
Y225197D03*
X929331Y307874D03*
Y292126D03*
Y276378D03*
X937205Y303937D03*
Y288189D03*
Y272441D03*
X929331Y339371D03*
Y323622D03*
X937205Y335434D03*
Y319685D03*
X929331Y395669D03*
X937205Y407480D03*
Y399606D03*
Y391732D03*
X929331Y450787D03*
X937205Y446850D03*
X929331Y427165D03*
Y419291D03*
Y411417D03*
X937205Y431102D03*
Y423228D03*
Y415354D03*
X929331Y498031D03*
Y482283D03*
Y466535D03*
X937205Y494094D03*
Y478346D03*
Y462598D03*
X929331Y545275D03*
Y529527D03*
Y513779D03*
X937205Y541338D03*
Y525590D03*
Y509842D03*
X929331Y592519D03*
Y576771D03*
Y561023D03*
X937205Y588582D03*
Y572834D03*
Y557086D03*
X929331Y639763D03*
Y624015D03*
Y608267D03*
X937205Y635826D03*
Y620078D03*
Y604330D03*
X929331Y687007D03*
Y671259D03*
Y655511D03*
X937205Y683070D03*
Y667322D03*
Y651574D03*
X929331Y718504D03*
Y702755D03*
X937205Y714567D03*
Y698818D03*
X954921Y16536D03*
X947047Y20473D03*
Y12599D03*
X954921Y63780D03*
X947047Y67717D03*
X954921Y40158D03*
Y32284D03*
X947047Y51969D03*
Y44095D03*
Y36221D03*
Y28347D03*
X954921Y111024D03*
Y95276D03*
Y79528D03*
X947047Y107087D03*
Y91339D03*
Y75591D03*
X954921Y158268D03*
Y142520D03*
Y126772D03*
X947047Y154331D03*
Y138583D03*
Y122835D03*
X954921Y205512D03*
Y189764D03*
Y174016D03*
X947047Y201575D03*
Y185827D03*
Y170079D03*
X954921Y252756D03*
Y237008D03*
Y221260D03*
X947047Y248819D03*
Y233071D03*
Y217323D03*
X954921Y300000D03*
Y284252D03*
Y268504D03*
X947047Y296063D03*
Y280315D03*
Y264567D03*
X954921Y339371D03*
Y331496D03*
Y315748D03*
X947047Y327559D03*
Y311811D03*
X954921Y395669D03*
X947047Y407480D03*
Y399606D03*
Y391732D03*
X954921Y442913D03*
X947047Y454724D03*
X954921Y427165D03*
Y419291D03*
Y411417D03*
X947047Y431102D03*
Y423228D03*
X954921Y490157D03*
Y474409D03*
Y458661D03*
X947047Y501968D03*
Y486220D03*
Y470472D03*
X954921Y553149D03*
Y537401D03*
Y521653D03*
Y505905D03*
X947047Y549212D03*
Y533464D03*
Y517716D03*
X954921Y600393D03*
Y584645D03*
Y568897D03*
X947047Y596456D03*
Y580708D03*
Y564960D03*
X954921Y647637D03*
Y631889D03*
Y616141D03*
X947047Y643700D03*
Y627952D03*
Y612204D03*
X954921Y694881D03*
Y679133D03*
Y663385D03*
X947047Y690944D03*
Y675196D03*
Y659448D03*
X954921Y710629D03*
X947047Y706692D03*
X1123031Y16536D03*
X1097441D03*
X1115157Y20473D03*
Y12599D03*
X1105315Y20473D03*
Y12599D03*
X1123031Y63780D03*
X1115157Y67717D03*
X1105315D03*
X1123031Y40158D03*
Y32284D03*
X1097441Y48032D03*
Y32284D03*
X1115157Y51969D03*
Y44095D03*
Y36221D03*
Y28347D03*
X1105315Y44095D03*
Y36221D03*
Y28347D03*
X1123031Y111024D03*
Y95276D03*
Y79528D03*
X1097441Y103150D03*
Y87402D03*
Y71654D03*
X1115157Y107087D03*
Y91339D03*
Y75591D03*
X1105315Y114961D03*
Y99213D03*
Y83465D03*
X1123031Y158268D03*
Y142520D03*
Y126772D03*
X1097441Y166142D03*
Y150394D03*
Y134646D03*
Y118898D03*
X1115157Y154331D03*
Y138583D03*
Y122835D03*
X1105315Y162205D03*
Y146457D03*
Y130709D03*
X1123031Y205512D03*
Y189764D03*
Y174016D03*
X1097441Y213386D03*
Y197638D03*
Y181890D03*
X1115157Y201575D03*
Y185827D03*
Y170079D03*
X1105315Y209449D03*
Y193701D03*
Y177953D03*
X1123031Y252756D03*
Y237008D03*
Y221260D03*
X1097441Y260630D03*
Y244882D03*
Y229134D03*
X1115157Y248819D03*
Y233071D03*
Y217323D03*
X1105315Y256693D03*
Y240945D03*
Y225197D03*
X1123031Y300000D03*
Y284252D03*
Y268504D03*
X1097441Y307874D03*
Y292126D03*
Y276378D03*
X1115157Y296063D03*
Y280315D03*
Y264567D03*
X1105315Y303937D03*
Y288189D03*
Y272441D03*
X1123031Y339371D03*
Y331496D03*
Y315748D03*
X1097441Y339371D03*
Y323622D03*
X1115157Y327559D03*
Y311811D03*
X1105315Y335434D03*
Y319685D03*
X1123031Y395669D03*
X1097441D03*
X1115157Y407480D03*
Y399606D03*
Y391732D03*
X1105315Y407480D03*
Y399606D03*
Y391732D03*
X1123031Y442913D03*
X1097441Y450787D03*
X1115157Y454724D03*
X1105315Y446850D03*
X1123031Y427165D03*
Y419291D03*
Y411417D03*
X1097441Y427165D03*
Y419291D03*
Y411417D03*
X1115157Y431102D03*
Y423228D03*
X1105315Y431102D03*
Y423228D03*
Y415354D03*
X1123031Y490157D03*
Y474409D03*
Y458661D03*
X1097441Y498031D03*
Y482283D03*
Y466535D03*
X1115157Y501968D03*
Y486220D03*
Y470472D03*
X1105315Y494094D03*
Y478346D03*
Y462598D03*
X1123031Y553149D03*
Y537401D03*
Y521653D03*
Y505905D03*
X1097441Y545275D03*
Y529527D03*
Y513779D03*
X1115157Y549212D03*
Y533464D03*
Y517716D03*
X1105315Y541338D03*
Y525590D03*
Y509842D03*
X1123031Y600393D03*
Y584645D03*
Y568897D03*
X1097441Y592519D03*
Y576771D03*
Y561023D03*
X1115157Y596456D03*
Y580708D03*
Y564960D03*
X1105315Y588582D03*
Y572834D03*
Y557086D03*
X1123031Y647637D03*
Y631889D03*
Y616141D03*
X1097441Y639763D03*
Y624015D03*
Y608267D03*
X1115157Y643700D03*
Y627952D03*
Y612204D03*
X1105315Y635826D03*
Y620078D03*
Y604330D03*
X1123031Y694881D03*
Y679133D03*
Y663385D03*
X1097441Y687007D03*
Y671259D03*
Y655511D03*
X1115157Y690944D03*
Y675196D03*
Y659448D03*
X1105315Y683070D03*
Y667322D03*
Y651574D03*
X1123031Y710629D03*
X1097441Y718504D03*
Y702755D03*
X1115157Y706692D03*
X1105315Y714567D03*
Y698818D03*
G54D43*
X974016Y1642401D03*
X986614D03*
X974016Y1636496D03*
Y1648307D03*
X986614Y1636496D03*
Y1648307D03*
X1030709Y1619764D03*
X1014961D03*
X1002362D03*
Y1613858D03*
X1014961D03*
X1030709D03*
X1002362Y1642401D03*
X1014961D03*
X1030709D03*
X1002362Y1625669D03*
Y1636496D03*
Y1648307D03*
X1014961Y1625669D03*
Y1636496D03*
Y1648307D03*
X1030709Y1625669D03*
Y1636496D03*
Y1648307D03*
X1043307Y1619764D03*
Y1613858D03*
Y1642401D03*
Y1625669D03*
Y1636496D03*
Y1648307D03*
X1101457Y1601181D03*
X1119685D03*
X1108150D03*
X1126378D03*
G54D31*
X313312Y98705D03*
X317812Y98905D03*
X385210Y1166347D03*
X450984Y124507D03*
X436811D03*
X479830D03*
X465157D03*
X550197D03*
X536023D03*
X521850D03*
X564370D03*
X753883Y929689D03*
Y937689D03*
Y945689D03*
X756250Y1140250D03*
X838521Y41568D03*
X838043Y37217D03*
X929331Y63780D03*
Y40158D03*
Y24410D03*
X937205Y51969D03*
X929331Y111024D03*
Y95276D03*
Y79528D03*
X937205Y107087D03*
Y91339D03*
Y75591D03*
X929331Y158268D03*
Y142520D03*
Y126772D03*
X937205Y154331D03*
Y138583D03*
Y122835D03*
X929331Y205512D03*
Y189764D03*
Y174016D03*
X937205Y201575D03*
Y185827D03*
Y170079D03*
X929331Y252756D03*
Y237008D03*
Y221260D03*
X937205Y248819D03*
Y233071D03*
Y217323D03*
X929331Y300000D03*
Y284252D03*
Y268504D03*
X937205Y296063D03*
Y280315D03*
Y264567D03*
X929331Y331496D03*
Y315748D03*
X937205Y327559D03*
Y311811D03*
X929331Y403543D03*
Y442913D03*
X937205Y454724D03*
X929331Y490157D03*
Y474409D03*
Y458661D03*
X937205Y501968D03*
Y486220D03*
Y470472D03*
X929331Y553149D03*
Y537401D03*
Y521653D03*
Y505905D03*
X937205Y549212D03*
Y533464D03*
Y517716D03*
X929331Y600393D03*
Y584645D03*
Y568897D03*
X937205Y596456D03*
Y580708D03*
Y564960D03*
X929331Y647637D03*
Y631889D03*
Y616141D03*
X937205Y643700D03*
Y627952D03*
Y612204D03*
X929331Y694881D03*
Y679133D03*
Y663385D03*
X937205Y690944D03*
Y675196D03*
Y659448D03*
X929331Y710629D03*
X937205Y706692D03*
X942925Y1369010D03*
X928384Y1346435D03*
X932559Y1360137D03*
X928439Y1360167D03*
X954921Y48032D03*
Y24410D03*
Y103150D03*
Y87402D03*
Y71654D03*
X947047Y114961D03*
Y99213D03*
Y83465D03*
X954921Y166142D03*
Y150394D03*
Y134646D03*
Y118898D03*
X947047Y162205D03*
Y146457D03*
Y130709D03*
X954921Y213386D03*
Y197638D03*
Y181890D03*
X947047Y209449D03*
Y193701D03*
Y177953D03*
X954921Y260630D03*
Y244882D03*
Y229134D03*
X947047Y256693D03*
Y240945D03*
Y225197D03*
X954921Y307874D03*
Y292126D03*
Y276378D03*
X947047Y303937D03*
Y288189D03*
Y272441D03*
X954921Y323622D03*
X947047Y335434D03*
Y319685D03*
X954921Y403543D03*
Y450787D03*
X947047Y446850D03*
Y415354D03*
X954921Y498031D03*
Y482283D03*
Y466535D03*
X947047Y494094D03*
Y478346D03*
Y462598D03*
X954921Y545275D03*
Y529527D03*
Y513779D03*
X947047Y541338D03*
Y525590D03*
Y509842D03*
X954921Y592519D03*
Y576771D03*
Y561023D03*
X947047Y588582D03*
Y572834D03*
Y557086D03*
X954921Y639763D03*
Y624015D03*
Y608267D03*
X947047Y635826D03*
Y620078D03*
Y604330D03*
X954921Y687007D03*
Y671259D03*
Y655511D03*
X947047Y683070D03*
Y667322D03*
Y651574D03*
X954921Y718504D03*
Y702755D03*
X947047Y714567D03*
Y698818D03*
X947125Y1369010D03*
X1034916Y-82413D03*
Y-87913D03*
X1011984Y-83066D03*
X1012174Y-88726D03*
X1050100Y392600D03*
Y397600D03*
Y402600D03*
X1044600Y392500D03*
Y397500D03*
Y402500D03*
Y407500D03*
X1050100Y407600D03*
X1044680Y921400D03*
X1097441Y63780D03*
X1123031Y48032D03*
Y24410D03*
X1097441Y40158D03*
Y24410D03*
X1105315Y51969D03*
X1123031Y103150D03*
Y87402D03*
Y71654D03*
X1097441Y111024D03*
Y95276D03*
Y79528D03*
X1115157Y114961D03*
Y99213D03*
Y83465D03*
X1105315Y107087D03*
Y91339D03*
Y75591D03*
X1123031Y166142D03*
Y150394D03*
Y134646D03*
Y118898D03*
X1097441Y158268D03*
Y142520D03*
Y126772D03*
X1115157Y162205D03*
Y146457D03*
Y130709D03*
X1105315Y154331D03*
Y138583D03*
Y122835D03*
X1123031Y213386D03*
Y197638D03*
Y181890D03*
X1097441Y205512D03*
Y189764D03*
Y174016D03*
X1115157Y209449D03*
Y193701D03*
Y177953D03*
X1105315Y201575D03*
Y185827D03*
Y170079D03*
X1123031Y260630D03*
Y244882D03*
Y229134D03*
X1097441Y252756D03*
Y237008D03*
Y221260D03*
X1115157Y256693D03*
Y240945D03*
Y225197D03*
X1105315Y248819D03*
Y233071D03*
Y217323D03*
X1123031Y307874D03*
Y292126D03*
Y276378D03*
X1097441Y300000D03*
Y284252D03*
Y268504D03*
X1115157Y303937D03*
Y288189D03*
Y272441D03*
X1105315Y296063D03*
Y280315D03*
Y264567D03*
X1123031Y323622D03*
X1097441Y331496D03*
Y315748D03*
X1115157Y335434D03*
Y319685D03*
X1105315Y327559D03*
Y311811D03*
X1123031Y403543D03*
X1097441D03*
X1123031Y450787D03*
X1097441Y442913D03*
X1115157Y446850D03*
X1105315Y454724D03*
X1115157Y415354D03*
X1123031Y498031D03*
Y482283D03*
Y466535D03*
X1097441Y490157D03*
Y474409D03*
Y458661D03*
X1115157Y494094D03*
Y478346D03*
Y462598D03*
X1105315Y501968D03*
Y486220D03*
Y470472D03*
X1123031Y545275D03*
Y529527D03*
Y513779D03*
X1097441Y553149D03*
Y537401D03*
Y521653D03*
Y505905D03*
X1115157Y541338D03*
Y525590D03*
Y509842D03*
X1105315Y549212D03*
Y533464D03*
Y517716D03*
X1123031Y592519D03*
Y576771D03*
Y561023D03*
X1097441Y600393D03*
Y584645D03*
Y568897D03*
X1115157Y588582D03*
Y572834D03*
Y557086D03*
X1105315Y596456D03*
Y580708D03*
Y564960D03*
X1123031Y639763D03*
Y624015D03*
Y608267D03*
X1097441Y647637D03*
Y631889D03*
Y616141D03*
X1115157Y635826D03*
Y620078D03*
Y604330D03*
X1105315Y643700D03*
Y627952D03*
Y612204D03*
X1123031Y687007D03*
Y671259D03*
Y655511D03*
X1097441Y694881D03*
Y679133D03*
Y663385D03*
X1115157Y683070D03*
Y667322D03*
Y651574D03*
X1105315Y690944D03*
Y675196D03*
Y659448D03*
X1123031Y718504D03*
Y702755D03*
X1097441Y710629D03*
X1115157Y714567D03*
Y698818D03*
X1105315Y706692D03*
X1119159Y878130D03*
Y873130D03*
Y868130D03*
X1116159Y870630D03*
Y875630D03*
X1259800Y631998D03*
Y619498D03*
Y1072254D03*
Y1084754D03*
X1413400Y575000D03*
X1384013Y631998D03*
Y619498D03*
Y1072254D03*
Y1084754D03*
X1447834Y124507D03*
X1504527D03*
X1490354D03*
X1518701D03*
X1508225Y631998D03*
Y619498D03*
Y1072254D03*
Y1084754D03*
X1532874Y124507D03*
X1632438Y179242D03*
Y166742D03*
Y631998D03*
Y619498D03*
Y1072254D03*
Y1084754D03*
X1756650Y179242D03*
Y166742D03*
X1731650Y631998D03*
Y619498D03*
X1756650Y1072254D03*
Y1084754D03*
X1880863Y179242D03*
Y166742D03*
Y631998D03*
Y619498D03*
Y1072254D03*
X1884835Y1067400D03*
X1880863Y1084754D03*
G54D11*
X24508Y5500D03*
X20000Y60000D03*
X5500Y61492D03*
Y56492D03*
Y51492D03*
Y46492D03*
Y41492D03*
Y66492D03*
X20000Y80000D03*
Y100000D03*
X5500Y81492D03*
Y76492D03*
Y96492D03*
Y91492D03*
Y86492D03*
Y71492D03*
Y101492D03*
Y111492D03*
Y116492D03*
Y106492D03*
X20000Y120000D03*
Y140000D03*
Y160000D03*
X5500Y126492D03*
Y121492D03*
Y141492D03*
Y151492D03*
Y161492D03*
Y156492D03*
Y146492D03*
Y131492D03*
Y136492D03*
X20000Y180000D03*
Y200000D03*
X5500Y181492D03*
Y191492D03*
Y201492D03*
Y211492D03*
Y171492D03*
Y206492D03*
Y196492D03*
Y176492D03*
Y166492D03*
Y186492D03*
X20000Y220000D03*
Y240000D03*
Y260000D03*
X5500Y231492D03*
Y241492D03*
Y251492D03*
Y261492D03*
Y221492D03*
Y256492D03*
Y246492D03*
Y226492D03*
Y216492D03*
Y236492D03*
X20000Y280000D03*
Y300000D03*
X5500Y281492D03*
Y291492D03*
Y301492D03*
Y271492D03*
Y306492D03*
Y296492D03*
Y286492D03*
Y276492D03*
Y266492D03*
X20000Y320000D03*
Y340000D03*
X5500Y331492D03*
Y341492D03*
Y351492D03*
Y311492D03*
Y321492D03*
Y356492D03*
Y346492D03*
Y336492D03*
Y326492D03*
Y316492D03*
X20000Y360000D03*
Y380000D03*
Y400000D03*
X5500Y381492D03*
Y391492D03*
Y401492D03*
Y361492D03*
Y371492D03*
Y406492D03*
Y396492D03*
Y386492D03*
Y376492D03*
Y366492D03*
X20000Y420000D03*
Y440000D03*
X5500Y451492D03*
Y441492D03*
Y431492D03*
Y421492D03*
Y411492D03*
Y416492D03*
Y436492D03*
Y446492D03*
Y426492D03*
Y501492D03*
Y456492D03*
Y496492D03*
Y531492D03*
Y551492D03*
Y541492D03*
Y521492D03*
Y511492D03*
Y536492D03*
Y546492D03*
Y506492D03*
Y516492D03*
Y526492D03*
Y581492D03*
Y591492D03*
Y571492D03*
Y561492D03*
Y586492D03*
Y596492D03*
Y556492D03*
Y566492D03*
Y576492D03*
Y631492D03*
Y641492D03*
Y621492D03*
Y611492D03*
Y601492D03*
Y636492D03*
Y646492D03*
Y606492D03*
Y616492D03*
Y626492D03*
Y681492D03*
Y691492D03*
Y671492D03*
Y661492D03*
Y651492D03*
Y686492D03*
Y696492D03*
Y656492D03*
Y666492D03*
Y676492D03*
Y731492D03*
Y741492D03*
Y721492D03*
Y711492D03*
Y701492D03*
Y736492D03*
Y706492D03*
Y716492D03*
Y726492D03*
Y781492D03*
Y791492D03*
Y771492D03*
Y761492D03*
Y751492D03*
Y786492D03*
Y746492D03*
Y756492D03*
Y766492D03*
Y776492D03*
Y831492D03*
Y841492D03*
Y821492D03*
Y811492D03*
Y801492D03*
Y836492D03*
Y796492D03*
Y806492D03*
Y816492D03*
Y826492D03*
Y881492D03*
Y871492D03*
Y861492D03*
Y851492D03*
Y886492D03*
Y846492D03*
Y856492D03*
Y866492D03*
Y876492D03*
X15000Y930000D03*
Y920000D03*
X25000Y930000D03*
Y920000D03*
X5500Y931492D03*
Y921492D03*
Y911492D03*
Y901492D03*
Y891492D03*
Y936492D03*
Y896492D03*
Y906492D03*
Y916492D03*
Y926492D03*
X15000Y980000D03*
Y970000D03*
Y960000D03*
Y950000D03*
Y940000D03*
X25000D03*
Y950000D03*
Y960000D03*
Y970000D03*
Y980000D03*
X5500Y976492D03*
Y981492D03*
Y986492D03*
Y966492D03*
Y956492D03*
Y961492D03*
Y971492D03*
Y951492D03*
Y941492D03*
Y946492D03*
X15000Y1030000D03*
Y1020000D03*
Y1010000D03*
Y1000000D03*
Y990000D03*
X25000D03*
Y1000000D03*
Y1010000D03*
Y1020000D03*
X5500Y991492D03*
Y996492D03*
Y1001492D03*
Y1006492D03*
Y1026492D03*
Y1016492D03*
Y1011492D03*
Y1021492D03*
Y1031492D03*
X25000Y1040000D03*
Y1080000D03*
Y1070000D03*
Y1060000D03*
Y1050000D03*
X5500Y1036492D03*
Y1066492D03*
Y1056492D03*
Y1046492D03*
Y1041492D03*
Y1051492D03*
Y1061492D03*
Y1071492D03*
Y1081492D03*
Y1076492D03*
X25000Y1090000D03*
X5500Y1121492D03*
Y1131492D03*
Y1111492D03*
Y1101492D03*
Y1091492D03*
Y1086492D03*
Y1096492D03*
Y1106492D03*
Y1116492D03*
Y1126492D03*
Y1171492D03*
Y1161492D03*
Y1151492D03*
Y1141492D03*
Y1136492D03*
Y1146492D03*
Y1156492D03*
Y1166492D03*
Y1176492D03*
Y1221492D03*
Y1211492D03*
Y1201492D03*
Y1191492D03*
Y1181492D03*
Y1186492D03*
Y1196492D03*
Y1206492D03*
Y1216492D03*
Y1226492D03*
X17500Y1270000D03*
Y1260000D03*
Y1250000D03*
Y1240000D03*
X5500Y1271492D03*
Y1261492D03*
Y1251492D03*
Y1241492D03*
Y1231492D03*
Y1236492D03*
Y1246492D03*
Y1256492D03*
Y1266492D03*
Y1276492D03*
X17500Y1290000D03*
Y1280000D03*
Y1300000D03*
Y1310000D03*
X5500Y1321492D03*
Y1311492D03*
Y1301492D03*
Y1291492D03*
Y1281492D03*
Y1286492D03*
Y1296492D03*
Y1306492D03*
Y1316492D03*
X17500Y1320000D03*
Y1360000D03*
Y1350000D03*
Y1330000D03*
Y1340000D03*
X8983Y1368303D03*
X13983D03*
X18983D03*
X23983D03*
X5500Y1361492D03*
Y1351492D03*
Y1341492D03*
Y1331492D03*
Y1336492D03*
Y1346492D03*
Y1356492D03*
Y1326492D03*
X60000Y20000D03*
X29508Y5500D03*
X39508D03*
X34508D03*
X44508D03*
X64508D03*
X69508D03*
X54508D03*
X49508D03*
X59508D03*
X60000Y40000D03*
X40000D03*
X60000Y60000D03*
X40000D03*
Y80000D03*
X60000D03*
Y100000D03*
X40000D03*
X60000Y120000D03*
X40000D03*
Y140000D03*
X60000D03*
Y160000D03*
X40000D03*
X38500Y202000D03*
X64487Y212761D03*
X56000Y237000D03*
X73437Y247161D03*
X49437Y254661D03*
X73437Y234661D03*
X62000Y276500D03*
X40000Y280000D03*
Y300000D03*
X60000D03*
Y320000D03*
X40000D03*
X60000Y340000D03*
X40000D03*
Y360000D03*
X35000Y446500D03*
X50500Y545500D03*
X58346Y516473D03*
X54088Y512336D03*
X39853Y512373D03*
X44111Y516510D03*
X40000Y560000D03*
Y580000D03*
Y600000D03*
Y620000D03*
X39000Y646000D03*
X30697Y679553D03*
X73437Y687417D03*
X64487Y665417D03*
X31043Y689115D03*
X30676Y663764D03*
X49500Y729000D03*
X49437Y707417D03*
X73437Y699917D03*
X31064Y704904D03*
X69500Y777000D03*
X51000Y755500D03*
X38500Y800500D03*
X39000Y834500D03*
X49000Y811000D03*
X51000Y846000D03*
X40000Y930000D03*
Y920000D03*
Y970000D03*
Y960000D03*
Y950000D03*
Y940000D03*
X50000Y1030000D03*
X70000Y1020000D03*
X40000Y1000000D03*
Y990000D03*
X50000Y1060000D03*
X64487Y1118173D03*
X30256Y1116731D03*
X30670Y1132472D03*
X30644Y1157871D03*
X49437Y1160173D03*
X73437Y1140173D03*
Y1152673D03*
X30623Y1142082D03*
X52000Y1186000D03*
X71500Y1205000D03*
X45800Y1306100D03*
X37500Y1360000D03*
X27500D03*
X28983Y1368303D03*
X33983D03*
X38983D03*
X43983D03*
X48983D03*
X53983D03*
X58983D03*
X63983D03*
X68983D03*
X114508Y5500D03*
X119508D03*
X104508D03*
X94508D03*
X84508D03*
X74508D03*
X79508D03*
X89508D03*
X99508D03*
X109508D03*
X80000Y80000D03*
X100000D03*
X120000D03*
Y100000D03*
X100000D03*
X80000D03*
X120000Y120000D03*
X100000D03*
X80000D03*
X86500Y157500D03*
X80000Y140000D03*
X118437Y141870D03*
X78500Y169500D03*
X111437Y195492D03*
X106937Y198543D03*
Y207992D03*
X111437Y165492D03*
Y180492D03*
X74937Y187461D03*
X92287Y194661D03*
X86637Y194861D03*
X82000Y219000D03*
X111437Y245492D03*
Y235492D03*
X106937Y217441D03*
X111437Y265492D03*
Y275492D03*
X89237Y276861D03*
X95437Y300161D03*
X96000Y336500D03*
X80000Y320000D03*
Y340000D03*
X118437Y314114D03*
X89000Y403500D03*
X100000Y420000D03*
X120000Y440000D03*
X100000D03*
Y460000D03*
X120000D03*
Y480000D03*
X100000D03*
X120000Y500000D03*
X100000D03*
X104500Y515500D03*
X120500Y524000D03*
X86500Y522000D03*
X100000Y541500D03*
X87000Y541000D03*
X89000Y557500D03*
X108500Y572000D03*
X88000Y577500D03*
X118753Y594626D03*
X88000Y602500D03*
X111437Y648248D03*
Y633248D03*
Y618248D03*
X92287Y647417D03*
X86637Y647617D03*
X74937Y640217D03*
X81500Y672000D03*
X106937Y670197D03*
X111437Y688248D03*
X106937Y660748D03*
Y651299D03*
X111437Y728248D03*
Y718248D03*
Y698248D03*
X89237Y729617D03*
X75500Y757500D03*
X94000Y789000D03*
X118437Y766870D03*
X95437Y752917D03*
X89500Y802500D03*
X90000Y858000D03*
X100000Y880000D03*
Y900000D03*
X120000D03*
Y920000D03*
X100000D03*
X120000Y940000D03*
X83100Y984800D03*
X78600D03*
X83100Y980300D03*
X78600D03*
X100000Y940000D03*
X120000Y1025000D03*
X85000Y1020000D03*
X78600Y989300D03*
X83100D03*
X74000Y1074000D03*
X85000Y1060000D03*
X111437Y1071004D03*
X118437Y1047382D03*
X81000Y1124500D03*
X106937Y1122953D03*
Y1113504D03*
Y1104055D03*
X111437Y1101004D03*
Y1086004D03*
X92287Y1100173D03*
X86637Y1100373D03*
X74937Y1092973D03*
X111437Y1171004D03*
Y1151004D03*
Y1141004D03*
X118437Y1219626D03*
X111437Y1181004D03*
X89237Y1182373D03*
X95437Y1205673D03*
X98500Y1241000D03*
X90000Y1252500D03*
X86000Y1282000D03*
X93000Y1319000D03*
X73983Y1368303D03*
X78983D03*
X83983D03*
X88983D03*
X93983D03*
X98983D03*
X107374Y1369303D03*
X112374D03*
X117374D03*
X160000Y20000D03*
X134508Y5500D03*
X124508D03*
X129508D03*
X169508D03*
X159508D03*
X149508D03*
X139508D03*
X154508D03*
X164508D03*
X144508D03*
X160000Y60000D03*
Y40000D03*
X140000D03*
Y60000D03*
X160000Y100000D03*
Y80000D03*
X140000D03*
Y100000D03*
X160000Y140000D03*
X140000D03*
X160000Y120000D03*
X140000D03*
X156500Y170500D03*
X130500Y211500D03*
X160500Y190000D03*
X160000Y180000D03*
X129000Y259000D03*
X142687Y237161D03*
X128000Y288500D03*
X160000Y280000D03*
X140000Y300000D03*
X160000D03*
X140000Y320000D03*
X160000D03*
X140000Y440000D03*
Y460000D03*
Y480000D03*
Y500000D03*
X142500Y515500D03*
X150000Y526500D03*
X164107Y512331D03*
X168365Y516368D03*
X135000Y588000D03*
X167000Y613000D03*
X147500Y605500D03*
X142687Y689917D03*
X135200Y738400D03*
X153705Y744831D03*
X153714Y720741D03*
X153757Y710653D03*
X140372Y732370D03*
X160000Y880000D03*
Y900000D03*
X140000Y920000D03*
X160000D03*
Y940000D03*
X140000D03*
X156000Y1032000D03*
X134000Y1064000D03*
X153000Y1105000D03*
X132000Y1117000D03*
X142687Y1142673D03*
X154363Y1161725D03*
X153716Y1174793D03*
X170000Y1190500D03*
X153824Y1197248D03*
X153932Y1182940D03*
X122374Y1369303D03*
X127374D03*
X132374D03*
X137374D03*
X142374D03*
X147374D03*
X152374D03*
X157374D03*
X162374D03*
X167374D03*
X200000Y20000D03*
X180000D03*
X209508Y5500D03*
X199508D03*
X189508D03*
X179508D03*
X204508D03*
X214508D03*
X174508D03*
X184508D03*
X194508D03*
X200000Y40000D03*
X180000D03*
X200000Y60000D03*
X180000D03*
Y80000D03*
X200000D03*
Y100000D03*
X180000D03*
Y120000D03*
X200000D03*
Y140000D03*
X180000D03*
X216500Y194756D03*
X210849Y194861D03*
X199149Y187461D03*
X188699Y212561D03*
X206000Y219000D03*
X180500Y237000D03*
X197649Y234661D03*
X173649Y254661D03*
X197649Y247161D03*
X180000Y300000D03*
X213449Y276861D03*
X180000Y320000D03*
Y340000D03*
X200000D03*
X178342Y512294D03*
X182600Y516331D03*
X210000Y644000D03*
X216499Y636917D03*
X199149Y631217D03*
X210849Y638617D03*
X206000Y672000D03*
X197649Y687417D03*
X213449Y729617D03*
X173649Y707417D03*
X197649Y699917D03*
X180000Y860000D03*
Y880000D03*
Y920000D03*
Y900000D03*
X215563Y1001225D03*
X203563D03*
X207563D03*
X211563D03*
X211000Y1065000D03*
X203500Y1124500D03*
X216499Y1100173D03*
X210849Y1100373D03*
X199149Y1092973D03*
X188399Y1113873D03*
X175000Y1143000D03*
X173649Y1160173D03*
X193423Y1140945D03*
X197649Y1152673D03*
X213449Y1182373D03*
X181000Y1261000D03*
X190000Y1320000D03*
X200000D03*
X210000D03*
Y1300000D03*
Y1310000D03*
X200000D03*
X190000D03*
X172374Y1369303D03*
X177374D03*
X182374D03*
X187374D03*
X192374D03*
X197374D03*
X202374D03*
X207374D03*
X212374D03*
X217374D03*
X260000Y20000D03*
X220000D03*
X240000D03*
X259508Y5500D03*
X249508D03*
X239508D03*
X229508D03*
X219508D03*
X224508D03*
X234508D03*
X244508D03*
X254508D03*
X264508D03*
X260000Y60000D03*
Y40000D03*
X240000D03*
X220000D03*
Y60000D03*
X240000D03*
X260000Y100000D03*
Y80000D03*
X240000D03*
X220000D03*
Y100000D03*
X240000D03*
X260000Y140000D03*
Y120000D03*
X240000D03*
X220000D03*
X242649Y141870D03*
X262000Y209000D03*
X235649Y195492D03*
X231991Y198543D03*
X231149Y207992D03*
X235649Y165492D03*
Y180492D03*
X253000Y260000D03*
X266899Y237161D03*
X235649Y245492D03*
Y235492D03*
X231149Y217441D03*
X255000Y280000D03*
X235649Y265492D03*
Y275492D03*
X219649Y300161D03*
X242649Y314114D03*
X220000Y360000D03*
X240000Y380000D03*
X220000D03*
Y400000D03*
X240000D03*
Y420000D03*
X220000D03*
Y440000D03*
X240000D03*
Y460000D03*
X220000D03*
Y480000D03*
X240000D03*
Y500000D03*
X220000D03*
Y520000D03*
X243051Y594626D03*
X235649Y648248D03*
Y633248D03*
Y618248D03*
X255500Y664500D03*
X231149Y670197D03*
X235649Y688248D03*
X231149Y660748D03*
Y651299D03*
X266899Y689917D03*
X235649Y728248D03*
Y718248D03*
Y698248D03*
X264739Y732114D03*
X242649Y766870D03*
X219649Y752917D03*
X248500Y788500D03*
X225000Y840000D03*
X245000D03*
X265000Y795000D03*
X225000Y815000D03*
Y880000D03*
X245000D03*
X225000Y860000D03*
X245000D03*
X225000Y900000D03*
X245000D03*
Y940000D03*
X263000Y1023000D03*
X219563Y1001225D03*
X223563D03*
X263000Y1047000D03*
X235649Y1071004D03*
X242649Y1047382D03*
X231149Y1122953D03*
Y1113504D03*
Y1104055D03*
X235649Y1101004D03*
Y1086004D03*
Y1171004D03*
Y1151004D03*
X235300Y1142700D03*
X266899Y1141173D03*
X255000Y1207500D03*
X242649Y1219626D03*
X235649Y1181004D03*
X219649Y1205673D03*
X257000Y1253000D03*
X220000Y1270000D03*
Y1320000D03*
X230000D03*
X240000D03*
X250000D03*
X260000D03*
X220000Y1280000D03*
X230000D03*
X250000Y1290000D03*
X240000D03*
X230000D03*
X220000D03*
Y1300000D03*
X230000D03*
X240000D03*
X250000D03*
X260000D03*
Y1310000D03*
X250000D03*
X240000D03*
X230000D03*
X220000D03*
X222374Y1369303D03*
X227374D03*
X232374D03*
X237374D03*
X242374D03*
X247374D03*
X252374D03*
X257374D03*
X262374D03*
X300000Y20000D03*
X280000D03*
X309508Y5500D03*
X299508D03*
X289508D03*
X279508D03*
X269508D03*
X304508D03*
X314508D03*
X274508D03*
X284508D03*
X294508D03*
X300000Y40000D03*
X280000Y60000D03*
Y40000D03*
Y100000D03*
Y80000D03*
X312355Y72855D03*
X280000Y140000D03*
Y120000D03*
X270000Y179500D03*
X285500Y189500D03*
X283000Y181000D03*
X314329Y212420D03*
X304500Y237000D03*
X297862Y254661D03*
X300000Y300000D03*
Y320000D03*
Y340000D03*
X295000Y400000D03*
Y440000D03*
Y460000D03*
X302513Y512294D03*
X306771Y516331D03*
X292536Y516368D03*
X288278Y512331D03*
X282263Y589225D03*
X270263D03*
X274263D03*
X286263D03*
X290263D03*
X278263D03*
X277000Y618500D03*
X275000Y647000D03*
X294500Y607500D03*
X284000D03*
X312912Y665417D03*
X277972Y744575D03*
X297862Y707417D03*
X277981Y720485D03*
X278024Y710397D03*
X286000Y810500D03*
X305200Y1068400D03*
X295200Y1078400D03*
Y1058400D03*
X281000Y1105000D03*
X312912Y1118273D03*
X304500Y1142500D03*
X302452Y1165162D03*
X278577Y1161725D03*
X277930Y1175001D03*
X306000Y1182500D03*
X278076Y1197355D03*
X278146Y1182940D03*
X301000Y1231000D03*
X267374Y1369303D03*
X272374D03*
X277374D03*
X282374D03*
X287374D03*
X292374D03*
X297374D03*
X302374D03*
X307374D03*
X312374D03*
X360000Y20000D03*
X340000D03*
X320000D03*
X359508Y5500D03*
X349508D03*
X339508D03*
X329508D03*
X319508D03*
X324508D03*
X334508D03*
X344508D03*
X354508D03*
X360000Y40000D03*
X340000D03*
X320000D03*
X355200Y58400D03*
X346245Y58745D03*
X353001Y81799D03*
X351000Y70700D03*
X328000Y150500D03*
X333021Y129679D03*
X359862Y165492D03*
Y180492D03*
Y195492D03*
X355362Y198543D03*
Y207992D03*
X323362Y187461D03*
X340712Y194661D03*
X335062Y194861D03*
X333500Y219000D03*
X359862Y245492D03*
Y235492D03*
X355362Y217441D03*
X321862Y234661D03*
Y247161D03*
X359862Y265492D03*
Y275492D03*
X337662Y276861D03*
X343862Y300161D03*
X352000Y331000D03*
X320000Y340000D03*
X350000Y440000D03*
X330000D03*
X350000Y500000D03*
Y480000D03*
Y460000D03*
X330000D03*
Y540000D03*
X350000D03*
Y520000D03*
X333000Y560000D03*
Y580000D03*
X350000Y560000D03*
X333000Y604000D03*
X359862Y648248D03*
Y633248D03*
Y618248D03*
X340712Y647517D03*
X335062Y647617D03*
X323362Y640217D03*
X330000Y672000D03*
X355362Y670197D03*
X359862Y688248D03*
X355362Y660748D03*
Y651299D03*
X321862Y687417D03*
X359862Y728248D03*
Y718248D03*
Y698248D03*
X337662Y729617D03*
X321862Y699917D03*
X355000Y780500D03*
X320000Y750000D03*
X330000Y770000D03*
X347000Y788500D03*
X343862Y752917D03*
X361500Y901500D03*
X330000Y900000D03*
X360000Y960000D03*
Y940000D03*
X330000Y960000D03*
X322000Y988500D03*
X362000Y1017000D03*
X328000Y1061000D03*
X359862Y1071004D03*
X355362Y1122953D03*
Y1113504D03*
Y1104055D03*
X359862Y1101004D03*
Y1086004D03*
X340812Y1100273D03*
X335062Y1100373D03*
X323362Y1092973D03*
X358518Y1171114D03*
X359862Y1151004D03*
Y1141004D03*
X321862Y1140173D03*
Y1152673D03*
X327500Y1197000D03*
X359862Y1181004D03*
X337662Y1182373D03*
X343862Y1205673D03*
X353000Y1231000D03*
X330000Y1302000D03*
X333983Y1368303D03*
X338983D03*
X343983D03*
X348983D03*
X353983D03*
X358983D03*
X363983D03*
X317374Y1369303D03*
X322374D03*
X327374D03*
X380000Y20000D03*
X395075Y18639D03*
Y13639D03*
X389508Y5500D03*
X379508D03*
X369508D03*
X364508D03*
X374508D03*
X384508D03*
X394508D03*
X380000Y60000D03*
Y40000D03*
X395075Y43639D03*
Y38639D03*
Y33639D03*
Y28639D03*
Y23639D03*
X399000Y62000D03*
X396000Y55500D03*
X396075Y50248D03*
X401000Y89000D03*
X400000Y80000D03*
X365162Y88731D03*
Y77731D03*
X388500Y153500D03*
X395500Y160500D03*
X366862Y141870D03*
X386000Y209000D03*
X390312Y237161D03*
X389000Y289000D03*
X385500Y313000D03*
X366862Y314114D03*
X390000Y500000D03*
X370000D03*
X390000Y540000D03*
Y520000D03*
X370000D03*
Y540000D03*
X389000Y594500D03*
X390000Y560000D03*
X370000D03*
X366862Y594626D03*
X395000Y631000D03*
X388000Y607000D03*
X410000Y692500D03*
X379000Y664000D03*
X391112Y689917D03*
X402129Y744503D03*
X388796Y732042D03*
X402138Y720413D03*
X402181Y710325D03*
X402500Y780500D03*
X366862Y766870D03*
X397000Y911000D03*
X380000Y960000D03*
Y940000D03*
X393500Y988500D03*
Y1017000D03*
X390000Y1055000D03*
X366862Y1047382D03*
X391112Y1142673D03*
X399474Y1166787D03*
X366862Y1219626D03*
X406037Y1192706D03*
X402403Y1188312D03*
X368983Y1368303D03*
X373983D03*
X378983D03*
X383983D03*
X388983D03*
X393983D03*
X398983D03*
X403983D03*
X408983D03*
X437124Y212661D03*
X447574Y187461D03*
X446074Y247161D03*
X422300Y254661D03*
X446074Y234661D03*
X430000Y545500D03*
X460000Y540000D03*
X426663Y512257D03*
X430921Y516294D03*
X416686Y516331D03*
X412428Y512294D03*
X460000Y600000D03*
X445000D03*
X440000Y560000D03*
X460000D03*
X440000Y613000D03*
X459274Y647617D03*
X447574Y640217D03*
X417000Y652500D03*
X454500Y672000D03*
X446074Y687417D03*
X437224Y665417D03*
X452500Y744500D03*
X437500Y744000D03*
X422074Y707417D03*
X446074Y699917D03*
X455000Y780000D03*
X445000D03*
X440000Y760000D03*
X445000Y798000D03*
X428000Y988500D03*
X424000Y1105000D03*
X418500Y1176800D03*
X437104Y1160696D03*
X450500Y1208500D03*
X424000Y1206000D03*
X454500Y1248500D03*
X460000Y1320000D03*
X440000D03*
X460000Y1300000D03*
X413983Y1368303D03*
X418983D03*
X423983D03*
X428983D03*
X433983D03*
X438983D03*
X443983D03*
X448983D03*
X453983D03*
X458983D03*
X476319Y144481D03*
X506750Y165324D03*
X480159Y201245D03*
X500184Y200328D03*
X497785Y178034D03*
X478306Y195593D03*
X461122Y194861D03*
X484074Y245492D03*
X478651Y220734D03*
X484074Y235492D03*
Y275492D03*
X481174Y265492D03*
X461874Y276861D03*
X468074Y300161D03*
X491074Y314114D03*
X470000Y400000D03*
Y380000D03*
Y430000D03*
X465000Y491000D03*
X506746Y512331D03*
X499000Y553000D03*
X491074Y594626D03*
X484074Y648248D03*
Y633248D03*
Y618248D03*
X464924Y647417D03*
X479574Y670197D03*
X484074Y688248D03*
X479574Y660748D03*
Y651299D03*
X484074Y728248D03*
Y718248D03*
Y698248D03*
X461874Y729617D03*
X461500Y769500D03*
X491074Y766870D03*
X468074Y752917D03*
X500000Y960000D03*
Y940000D03*
X480000Y960000D03*
Y940000D03*
X504000Y988500D03*
X462000D03*
X468000Y1047000D03*
X484074Y1071004D03*
X491074Y1047382D03*
X479574Y1113504D03*
Y1104055D03*
X484074Y1101004D03*
Y1086004D03*
X504724Y1118073D03*
X484074Y1171004D03*
Y1151004D03*
Y1141004D03*
X506700Y1141973D03*
X502500Y1211500D03*
X476373Y1219498D03*
X484074Y1181004D03*
X461874Y1182373D03*
X468074Y1205673D03*
X480000Y1320000D03*
X500000Y1300000D03*
X480000D03*
Y1280000D03*
X463983Y1368303D03*
X468983D03*
X473983D03*
X478983D03*
X483983D03*
X488983D03*
X493983D03*
X498983D03*
X503983D03*
X508983D03*
X519868Y242334D03*
X515500Y301000D03*
X550987Y262810D03*
X548500Y343000D03*
X515000Y322500D03*
X547500Y440000D03*
X520981Y512294D03*
X525239Y516331D03*
X511004Y516368D03*
X540000Y583000D03*
Y600000D03*
X520000D03*
X528000Y611000D03*
X532000Y623000D03*
X515324Y689917D03*
X526225Y744756D03*
X546287Y707417D03*
X512892Y732295D03*
X526277Y710578D03*
X526234Y720666D03*
X509000Y772000D03*
X555500Y852000D03*
X551500Y888000D03*
X523500Y883500D03*
X525000Y937000D03*
X525500Y967000D03*
X523000Y1045000D03*
X528500Y1073500D03*
X546287Y1160173D03*
X535320Y1152771D03*
X534874Y1139774D03*
X526523Y1177122D03*
X526501Y1166546D03*
X526388Y1197747D03*
X526367Y1183111D03*
X539000Y1309000D03*
X517374Y1369303D03*
X522374D03*
X527374D03*
X532374D03*
X537374D03*
X542374D03*
X547374D03*
X552374D03*
X557374D03*
X597051Y7699D03*
Y12699D03*
Y17699D03*
X604146Y5500D03*
X597051Y22699D03*
Y27699D03*
Y32699D03*
Y37699D03*
Y42699D03*
X589000Y64000D03*
X594000Y61500D03*
X596000Y56500D03*
X596051Y51090D03*
X603787Y207992D03*
X604517Y196263D03*
X603697Y182091D03*
X586719Y196888D03*
X568687Y187660D03*
X583487Y194861D03*
X588188Y216520D03*
X570287Y234661D03*
X563000Y217600D03*
X569009Y247887D03*
X592287Y300161D03*
X582758Y276861D03*
X590000Y342000D03*
X560000Y438500D03*
X594500Y462000D03*
X569529Y502127D03*
X592000Y595000D03*
X580000Y600000D03*
X560000D03*
X586000Y611000D03*
X589137Y647417D03*
X583487Y647617D03*
X571787Y640217D03*
X579000Y672000D03*
X603787Y670197D03*
Y660748D03*
Y651299D03*
X570287Y687417D03*
X561437Y665417D03*
X559000Y741000D03*
X586087Y729617D03*
X570287Y699917D03*
X603000Y781000D03*
X592287Y752917D03*
X604000Y897000D03*
X592000Y900500D03*
X589500Y988000D03*
X571000D03*
X575000Y1057500D03*
X586500Y1061500D03*
X586000Y1046500D03*
X575000Y1046000D03*
X561337Y1120873D03*
X583487Y1100373D03*
X571787Y1092973D03*
X589137Y1100173D03*
X603787Y1122953D03*
Y1113504D03*
Y1104055D03*
X570287Y1140173D03*
Y1152673D03*
X567500Y1189500D03*
X586087Y1182373D03*
X592287Y1205673D03*
X590000Y1247000D03*
X567374Y1369303D03*
X572374D03*
X577374D03*
X582374D03*
X587374D03*
X592374D03*
X597374D03*
X602374D03*
X562374D03*
X609146Y5500D03*
X619146D03*
X614146D03*
X629146D03*
X639146D03*
X649146D03*
X654146D03*
X644146D03*
X634146D03*
X624146D03*
X613500Y66000D03*
X634500Y77000D03*
X629024Y107633D03*
X614967Y134777D03*
X606718Y168580D03*
X639537Y237161D03*
X608287Y245492D03*
Y235492D03*
X649500Y285000D03*
X608287Y275492D03*
X607961Y263934D03*
X650000Y322500D03*
X615287Y314114D03*
X649000Y429500D03*
X643000Y549500D03*
X620153Y511994D03*
X634388Y511957D03*
X615100Y513287D03*
X638646Y515994D03*
X624411Y516031D03*
X615287Y594626D03*
X608287Y648248D03*
Y633248D03*
Y618248D03*
Y688248D03*
X639537Y689917D03*
X650659Y744673D03*
X608287Y728248D03*
Y718248D03*
Y698248D03*
X637326Y732212D03*
X650668Y720583D03*
X650711Y710495D03*
X631500Y774000D03*
X615287Y766870D03*
X642000Y889500D03*
X632000Y936000D03*
X654000Y911000D03*
X646500Y898500D03*
X634000Y988000D03*
X638500Y1046500D03*
X608287Y1071004D03*
X615287Y1047382D03*
X608287Y1101004D03*
Y1086004D03*
X643000Y1146173D03*
X608287Y1171004D03*
Y1151004D03*
Y1141004D03*
X651216Y1164051D03*
X615238Y1218951D03*
X608287Y1181004D03*
X650644Y1197038D03*
X650626Y1182447D03*
X617374Y1369303D03*
X622374D03*
X627374D03*
X632374D03*
X637374D03*
X642374D03*
X647374D03*
X652374D03*
X607374D03*
X612374D03*
X679146Y5500D03*
X689146D03*
X694146D03*
X684146D03*
X659146D03*
X669146D03*
X664146D03*
X674146D03*
X699146D03*
X700000Y60000D03*
X675000Y75500D03*
X697457Y107247D03*
X697483Y111500D03*
X661965Y106177D03*
X658500Y184500D03*
X695137Y189130D03*
X685545Y212806D03*
X689426Y236628D03*
X694500Y247161D03*
X670500Y254661D03*
X673500Y344000D03*
X698500Y415500D03*
X695500Y462500D03*
X670000Y531500D03*
X696000Y641717D03*
X694500Y687417D03*
X685550Y665417D03*
X670500Y707417D03*
X694500Y699917D03*
X691500Y778000D03*
X692500Y790500D03*
X678500Y776500D03*
X673500Y752000D03*
X696000Y1092973D03*
X685250Y1113673D03*
X667700Y1160173D03*
X694500Y1140173D03*
X692671Y1152747D03*
X668000Y1195000D03*
X680500Y1208500D03*
X698500Y1306500D03*
X667374Y1369303D03*
X672374D03*
X677374D03*
X682374D03*
X687374D03*
X692374D03*
X697374D03*
X702374D03*
X657374D03*
X662374D03*
X749146Y5500D03*
X709146D03*
X719146D03*
X729146D03*
X739146D03*
X744146D03*
X734146D03*
X724146D03*
X714146D03*
X704146D03*
X740000Y40000D03*
X720000D03*
Y60000D03*
X740000D03*
X724645Y138941D03*
X732500Y180492D03*
Y165492D03*
X728000Y207992D03*
Y198543D03*
X732100Y198373D03*
X707700Y194861D03*
X713350Y194661D03*
X728000Y217441D03*
X732500Y245492D03*
X731048Y238563D03*
X738361Y306612D03*
X732500Y275492D03*
Y265492D03*
X710300Y276861D03*
X716500Y300161D03*
X724000Y338500D03*
X748000Y368500D03*
X726000Y369000D03*
X732000Y374500D03*
Y383000D03*
X748500Y409000D03*
X721500Y462500D03*
X727500Y476000D03*
X724000Y583500D03*
X702500Y563000D03*
X739500Y594626D03*
X732500Y648248D03*
Y633248D03*
Y618248D03*
X713350Y647417D03*
X704500Y672000D03*
X728000Y670197D03*
X732500Y688248D03*
X728000Y660748D03*
Y651299D03*
X707700Y649117D03*
X732500Y728248D03*
Y718248D03*
Y698248D03*
X710300Y729617D03*
X748000Y783000D03*
X739500Y766870D03*
X716500Y752917D03*
X745000Y833000D03*
X704500Y795000D03*
X747656Y876717D03*
X709500Y894500D03*
X712000Y1046000D03*
X732500Y1071004D03*
X739500Y1047382D03*
X728000Y1122953D03*
Y1113504D03*
Y1104055D03*
X732500Y1101004D03*
Y1086004D03*
X713350Y1100173D03*
X707700Y1100373D03*
X716000Y1136000D03*
X732500Y1171004D03*
Y1151004D03*
Y1141004D03*
X739500Y1219626D03*
X732500Y1181004D03*
X710300Y1182373D03*
X716500Y1205673D03*
X747374Y1369303D03*
X742374D03*
X717374D03*
X722374D03*
X727374D03*
X732374D03*
X737374D03*
X707374D03*
X712374D03*
X795969Y-1374D03*
X759146Y5500D03*
X769146D03*
X774146D03*
X764146D03*
X754146D03*
X779146D03*
X789045Y11615D03*
X780000Y40000D03*
X760000D03*
Y60000D03*
X780000D03*
X752950Y213450D03*
X771500Y311000D03*
X764000Y439500D03*
X767500Y463500D03*
X772000Y479500D03*
X787000Y514000D03*
X798140Y630220D03*
X798210Y626440D03*
X798367Y622400D03*
X751750Y685300D03*
X793000Y828000D03*
Y851000D03*
X778000Y988500D03*
X762500D03*
X763000Y1075000D03*
X781000Y1373000D03*
X755500Y1374500D03*
X752500Y1370500D03*
X757287Y1380873D03*
Y1385873D03*
Y1390873D03*
Y1395873D03*
Y1400873D03*
Y1405873D03*
Y1410873D03*
Y1415873D03*
Y1420873D03*
X784000Y1443000D03*
X757287Y1425873D03*
Y1430873D03*
Y1435873D03*
Y1440873D03*
Y1445873D03*
X766156Y1462004D03*
X771156D03*
X790500Y1466500D03*
X786000Y1463500D03*
X756287Y1459264D03*
Y1454264D03*
X779547Y1463004D03*
X792902Y1477964D03*
Y1487964D03*
Y1497964D03*
Y1507964D03*
Y1517964D03*
Y1512964D03*
Y1472964D03*
Y1482964D03*
Y1492964D03*
Y1502964D03*
Y1562964D03*
Y1527964D03*
Y1537964D03*
Y1547964D03*
Y1557964D03*
Y1567964D03*
Y1522964D03*
Y1532964D03*
Y1542964D03*
Y1552964D03*
Y1612964D03*
Y1602964D03*
Y1592964D03*
Y1582964D03*
Y1572964D03*
Y1577964D03*
Y1587964D03*
Y1597964D03*
Y1607964D03*
X797902Y1652964D03*
X792902D03*
Y1642964D03*
Y1632964D03*
Y1622964D03*
Y1627964D03*
Y1637964D03*
Y1647964D03*
Y1617964D03*
X845961Y61762D03*
Y56762D03*
Y52762D03*
X846000Y116500D03*
X811500Y372000D03*
X800000Y400000D03*
X811500Y469500D03*
X846400Y469300D03*
X839000Y541000D03*
X839500Y560000D03*
X800867Y619400D03*
X803367Y622400D03*
X827500Y922500D03*
X839414Y1520763D03*
X833859Y1594095D03*
Y1608268D03*
X840945Y1598032D03*
X826772D03*
X840945Y1612205D03*
X826772D03*
X833859Y1622441D03*
Y1636614D03*
Y1650788D03*
X840945Y1626378D03*
X826772D03*
X840945Y1640551D03*
X826772D03*
X872642Y-140575D03*
Y-135575D03*
Y-130575D03*
Y-125575D03*
X890264Y-147256D03*
X880264D03*
X875264D03*
X885264D03*
X895264D03*
X882000Y-105500D03*
X872642Y-80575D03*
Y-120575D03*
Y-115575D03*
Y-110575D03*
Y-105575D03*
Y-100575D03*
Y-95575D03*
Y-90575D03*
Y-85575D03*
Y-30575D03*
Y-35575D03*
Y-40575D03*
Y-45575D03*
Y-50575D03*
Y-55575D03*
Y-60575D03*
Y-65575D03*
Y-70575D03*
Y-75575D03*
Y-20575D03*
Y-25575D03*
X885046Y20384D03*
X861101Y66680D03*
X862099Y61626D03*
Y56626D03*
X861961Y52762D03*
X852769Y66957D03*
X848769D03*
X856769D03*
X853961Y52762D03*
X849961D03*
X857961D03*
X874244Y37026D03*
Y44935D03*
X852769Y74957D03*
X856769D03*
X861142Y71026D03*
X852810Y71303D03*
X856810D03*
X853900Y89701D03*
X888500Y260500D03*
X850500Y266000D03*
X866000Y315000D03*
X856500Y373000D03*
X855500Y499500D03*
X871487Y463589D03*
X860092Y542405D03*
X867500Y643000D03*
X877000Y664500D03*
X868500Y665000D03*
X885600Y824400D03*
X867663Y818831D03*
X885301Y1358557D03*
X884746Y1350438D03*
X873495Y1370213D03*
X885300Y1371050D03*
X877300Y1432400D03*
X886500Y1432500D03*
X893158Y1516542D03*
X893050Y1489500D03*
X868791Y1478782D03*
X892682Y1520718D03*
X855092Y1535821D03*
X866621Y1544206D03*
X876378Y1594095D03*
X862205D03*
X848032D03*
X876378Y1608268D03*
X862205D03*
X848032D03*
X890552Y1598032D03*
X869292D03*
X855118D03*
X869292Y1612205D03*
X855118D03*
X876378Y1622441D03*
X862205D03*
X848032D03*
X876378Y1636614D03*
X862205D03*
X848032D03*
X876378Y1650788D03*
X862205D03*
X848032D03*
X869292Y1626378D03*
X855118D03*
X869292Y1640551D03*
X855118D03*
X910500Y-137500D03*
X940264Y-147256D03*
X930264D03*
X925264D03*
X935264D03*
X920264D03*
X910264D03*
X900264D03*
X905264D03*
X915264D03*
X902000Y-58000D03*
X909000Y89000D03*
X898000Y133000D03*
X911000Y305500D03*
X898000Y268000D03*
X915000Y879000D03*
X926185Y928342D03*
X924974Y933041D03*
X914876Y901029D03*
X937621Y915324D03*
X924563Y962945D03*
X919759Y970868D03*
X938009Y987330D03*
X941868Y952101D03*
X916446Y1035438D03*
X941640Y995820D03*
X929257Y1035883D03*
X932564Y1346100D03*
X904941Y1456941D03*
X918505Y1530405D03*
X918800Y1534500D03*
X897638Y1594095D03*
X960264Y-147256D03*
X950264D03*
X955264D03*
X965264D03*
X945264D03*
X990264D03*
X980264D03*
X970264D03*
X975264D03*
X985264D03*
X975500Y11500D03*
X974000Y402000D03*
Y523000D03*
X985500Y613500D03*
X978000Y677000D03*
X981580Y932678D03*
X976580Y986180D03*
X959400Y960300D03*
X987970Y1004157D03*
X955700Y1030700D03*
X977400Y1157900D03*
X977500Y1182300D03*
X962500Y1298500D03*
X988624Y1502923D03*
X951815Y1491459D03*
X1010264Y-147256D03*
X1000264D03*
X1005264D03*
X1015264D03*
X995264D03*
X1040264D03*
X1030264D03*
X1020264D03*
X1025264D03*
X1035264D03*
X1015582Y-69800D03*
X1014800Y-62100D03*
X999300Y-64400D03*
X1009100Y-48600D03*
X1035000Y-66800D03*
X1022618Y-36900D03*
X1023300Y-44200D03*
X1032053Y-34953D03*
X1038712Y-34812D03*
X1017600Y63600D03*
Y58900D03*
Y54200D03*
X993000Y108000D03*
X1036003Y93543D03*
X1038503Y97543D03*
X1033503D03*
Y102543D03*
Y107543D03*
Y112543D03*
X993000Y157000D03*
Y329000D03*
X998000Y378000D03*
X995000Y455000D03*
Y488000D03*
X1018322Y545207D03*
X1018300Y550000D03*
X993000Y635000D03*
X1025000Y817000D03*
X1028472Y834829D03*
X1027063Y850703D03*
X1014891Y943357D03*
X1013713Y974651D03*
X997694Y974940D03*
X1012494Y1033840D03*
X1018000Y1076500D03*
X1031400Y1124700D03*
X1019000Y1178000D03*
X1013400Y1137500D03*
X1021991Y1141526D03*
X1004294Y1137600D03*
X997500Y1192500D03*
X1006800Y1191200D03*
X1032500Y1248000D03*
X993500Y1317000D03*
X1031000Y1350500D03*
X1031474Y1354526D03*
X1060264Y-147256D03*
X1050264D03*
X1055264D03*
X1065264D03*
X1045264D03*
X1080264D03*
X1070264D03*
X1075264D03*
X1085264D03*
X1065621Y-85082D03*
X1084200Y-82300D03*
X1074400Y-81000D03*
X1070500Y-67900D03*
X1074400Y-39100D03*
X1079600Y-50700D03*
X1087700Y-37886D03*
X1045800Y-75936D03*
X1058333Y-72770D03*
X1061325Y-40378D03*
X1054625Y-40278D03*
X1078500Y99000D03*
X1043703Y112543D03*
Y107543D03*
Y102543D03*
X1041003Y93543D03*
X1043703Y97543D03*
X1078500Y135500D03*
X1043500Y310500D03*
X1048500Y346000D03*
X1058500Y368500D03*
X1045000Y364000D03*
X1042833Y434409D03*
X1047000Y492000D03*
X1079000Y477000D03*
X1058000D03*
X1045106Y561249D03*
X1058000Y616000D03*
X1073000Y676000D03*
X1047000Y751000D03*
X1045163Y840400D03*
X1082000Y815500D03*
X1054000Y866000D03*
X1075500Y848000D03*
X1072000Y1035000D03*
X1052000Y1054000D03*
X1054080Y1077680D03*
X1087700Y1125800D03*
X1078098Y1652768D03*
X1073098D03*
X1083098D03*
X1088098D03*
X1110264Y-147256D03*
X1100264D03*
X1090264D03*
X1105264D03*
X1095264D03*
X1130264D03*
X1120264D03*
X1115264D03*
X1125264D03*
X1135264D03*
X1134500Y-103500D03*
X1115000Y-77500D03*
X1097600Y-82462D03*
X1107700Y-76800D03*
X1114400Y-55662D03*
X1093900Y-64500D03*
X1113300Y-44100D03*
X1137446Y1024025D03*
Y1009852D03*
Y995679D03*
Y1038198D03*
X1124100Y1125100D03*
X1137446Y1167343D03*
Y1224036D03*
Y1209863D03*
Y1195690D03*
Y1181516D03*
Y1266556D03*
Y1252383D03*
Y1238209D03*
Y1309076D03*
Y1323249D03*
Y1294902D03*
Y1280729D03*
Y1365769D03*
Y1351595D03*
Y1337422D03*
Y1394115D03*
Y1408288D03*
Y1379942D03*
X1093098Y1652768D03*
X1133098D03*
X1123098D03*
X1113098D03*
X1103098D03*
X1108098D03*
X1118098D03*
X1128098D03*
X1098098D03*
X1170264Y-147256D03*
X1155264D03*
X1175602Y-137594D03*
Y-127594D03*
X1160264Y-147256D03*
X1150264D03*
X1140264D03*
X1145264D03*
X1175602Y-132594D03*
Y-142594D03*
X1165264Y-147256D03*
X1175602Y-117594D03*
Y-107594D03*
Y-97594D03*
Y-87594D03*
Y-77594D03*
Y-82594D03*
Y-92594D03*
Y-102594D03*
Y-112594D03*
Y-122594D03*
X1139500Y-58500D03*
X1150000Y-63000D03*
X1175602Y-67594D03*
Y-57594D03*
Y-47594D03*
Y-37594D03*
Y-32594D03*
Y-42594D03*
Y-52594D03*
Y-62594D03*
Y-72594D03*
Y-17594D03*
Y-27594D03*
X1180500Y4000D03*
X1176500Y-500D03*
X1175602Y-22594D03*
Y-12594D03*
Y-7594D03*
X1184088Y101360D03*
X1184141Y96794D03*
X1177500Y153500D03*
X1173500Y397000D03*
X1156500Y467000D03*
X1166500Y635000D03*
X1156500Y619000D03*
X1176835Y618934D03*
X1156500Y650000D03*
X1181000Y814000D03*
X1156500Y813000D03*
X1179000Y829500D03*
X1166500D03*
X1158500Y868500D03*
X1144580Y1078680D03*
X1172564Y1118373D03*
X1162000Y1371500D03*
X1169783Y1369303D03*
X1179783D03*
X1174783D03*
X1184783D03*
X1158673Y1417067D03*
Y1407067D03*
Y1397067D03*
Y1387067D03*
Y1377067D03*
Y1412067D03*
Y1402067D03*
Y1392067D03*
Y1382067D03*
Y1422067D03*
Y1442067D03*
Y1452067D03*
X1158500Y1468500D03*
X1158673Y1457067D03*
Y1447067D03*
Y1437067D03*
Y1427067D03*
Y1462067D03*
Y1432067D03*
X1153000Y1496000D03*
X1161000Y1474500D03*
X1166673Y1477941D03*
X1171673D03*
X1181673D03*
X1176673D03*
X1163000Y1612000D03*
X1141000Y1632000D03*
X1143098Y1652768D03*
X1183098D03*
X1173098D03*
X1163098D03*
X1153098D03*
X1158098D03*
X1168098D03*
X1178098D03*
X1138098D03*
X1148098D03*
X1228500Y12500D03*
X1191382Y5500D03*
X1196382D03*
X1186382D03*
X1201382D03*
X1211382D03*
X1221382D03*
X1231382D03*
X1226382D03*
X1216382D03*
X1206382D03*
X1204768Y64368D03*
X1199768D03*
X1209768D03*
X1204068Y50368D03*
Y45368D03*
X1203768Y60568D03*
Y55568D03*
X1224000Y104000D03*
X1199768Y69368D03*
X1204768D03*
X1209768D03*
X1204768Y85368D03*
X1199768D03*
X1209768D03*
Y89368D03*
X1199768D03*
X1204768D03*
X1186500Y220500D03*
X1224800Y225200D03*
X1219917Y239646D03*
X1232500Y541000D03*
X1197868Y730300D03*
X1194268D03*
Y723100D03*
Y726700D03*
X1197868Y723100D03*
Y726700D03*
X1192068Y712300D03*
X1195668D03*
X1192068Y715900D03*
X1195668D03*
Y719500D03*
X1192068D03*
X1188000Y753000D03*
X1192000Y869000D03*
X1232700Y950400D03*
X1229691Y1148580D03*
X1214500Y1320500D03*
X1220500Y1311000D03*
X1199783Y1369303D03*
X1209783D03*
X1219783D03*
X1229783D03*
X1189783D03*
X1224783D03*
X1214783D03*
X1204783D03*
X1194783D03*
X1194000Y1499000D03*
X1191673Y1477941D03*
X1201673D03*
X1214972Y1482642D03*
Y1517642D03*
Y1487642D03*
Y1497642D03*
Y1507642D03*
Y1512642D03*
Y1502642D03*
Y1492642D03*
X1206673Y1477941D03*
X1196673D03*
X1186673D03*
X1211673D03*
X1214972Y1567642D03*
Y1527642D03*
Y1537642D03*
Y1547642D03*
Y1557642D03*
Y1562642D03*
Y1552642D03*
Y1542642D03*
Y1532642D03*
Y1522642D03*
Y1577642D03*
Y1587642D03*
Y1597642D03*
Y1607642D03*
Y1612642D03*
Y1602642D03*
Y1592642D03*
Y1582642D03*
Y1572642D03*
Y1617642D03*
Y1627642D03*
Y1637642D03*
X1213098Y1652768D03*
X1193098D03*
X1203098D03*
X1208098D03*
X1214972Y1642642D03*
Y1632642D03*
X1188098Y1652768D03*
X1198098D03*
X1214972Y1622642D03*
Y1647642D03*
X1240500Y20000D03*
X1251382Y5500D03*
X1261382D03*
X1271382D03*
X1281382D03*
X1276382D03*
X1266382D03*
X1256382D03*
X1241382D03*
X1246382D03*
X1236382D03*
X1254000Y105000D03*
X1281500Y103500D03*
X1278900Y182823D03*
X1266400D03*
X1278421Y205974D03*
X1281603Y203340D03*
X1282106Y180492D03*
X1280800Y167200D03*
X1282287Y243489D03*
X1277606Y217441D03*
X1282106Y235492D03*
X1248193Y242618D03*
X1255600Y237300D03*
X1273200Y263700D03*
X1276200Y277400D03*
X1280000Y430000D03*
X1235796Y517450D03*
X1250011Y516707D03*
X1282106Y648248D03*
Y633248D03*
Y618248D03*
X1253800Y689600D03*
X1277606Y670197D03*
X1282106Y688248D03*
X1277606Y660748D03*
Y651299D03*
X1282106Y728248D03*
Y718248D03*
Y698248D03*
X1250475Y969248D03*
X1279081Y1071085D03*
X1277606Y1122953D03*
Y1113504D03*
Y1104055D03*
X1282106Y1101004D03*
Y1086004D03*
X1251250Y1141700D03*
X1282106Y1171004D03*
Y1151004D03*
Y1141004D03*
X1246557Y1148155D03*
X1249600Y1155800D03*
X1282106Y1181004D03*
X1257000Y1300000D03*
X1263500Y1318500D03*
X1249783Y1369303D03*
X1259783D03*
X1269783D03*
X1279783D03*
X1239783D03*
X1274783D03*
X1264783D03*
X1254783D03*
X1234783D03*
X1244783D03*
X1319000Y12000D03*
X1301382Y5500D03*
X1311382D03*
X1296382D03*
X1316382D03*
X1306382D03*
X1291382D03*
X1286382D03*
X1326382D03*
X1321382D03*
X1309000Y45500D03*
X1318500Y34500D03*
X1319100Y78800D03*
X1323521Y79179D03*
X1312999Y107280D03*
X1317661Y107896D03*
X1299569Y84272D03*
X1304563Y84309D03*
X1289000Y145400D03*
X1302074Y183779D03*
X1311200Y172661D03*
X1304293Y165909D03*
X1315838Y188804D03*
X1297507Y195492D03*
X1298700Y272800D03*
X1298500Y302900D03*
X1305000Y299400D03*
X1313000Y302900D03*
X1313915Y263541D03*
X1289000Y309500D03*
X1311000Y321000D03*
X1303500Y434000D03*
X1287000Y456000D03*
X1310000Y597000D03*
X1289106Y594626D03*
X1303800Y636417D03*
X1311200Y625417D03*
X1307500Y615417D03*
X1315400Y648017D03*
X1302500Y718917D03*
X1314000Y717417D03*
X1298500Y752417D03*
X1305000D03*
X1313000D03*
X1289106Y766870D03*
X1305000Y1041500D03*
X1289114Y1048624D03*
X1311200Y1078173D03*
X1305100Y1068173D03*
X1303800Y1089173D03*
X1315300Y1100773D03*
X1302500Y1171673D03*
X1313950Y1165990D03*
X1300065Y1206008D03*
X1305000Y1205173D03*
X1313000D03*
X1289106Y1219626D03*
X1299783Y1369303D03*
X1309783D03*
X1319783D03*
X1329783D03*
X1289783D03*
X1324783D03*
X1314783D03*
X1304783D03*
X1294783D03*
X1284783D03*
X1363579Y19821D03*
Y14821D03*
Y9821D03*
X1351382Y5500D03*
X1356382D03*
X1346382D03*
X1336382D03*
X1341382D03*
X1331382D03*
X1357500Y43500D03*
X1347500Y21000D03*
X1363579Y44821D03*
Y39821D03*
Y34821D03*
Y29821D03*
Y24821D03*
X1374000Y64500D03*
X1363579Y51618D03*
X1332500Y56500D03*
X1351201Y90099D03*
X1332934Y137712D03*
X1377463Y237100D03*
X1372000Y335000D03*
X1338000Y546500D03*
X1346363Y516578D03*
X1332148Y517321D03*
X1337500Y576500D03*
X1372272Y573560D03*
X1375463Y689917D03*
X1339500Y794000D03*
X1344000Y987500D03*
X1362000Y987000D03*
X1331070Y966090D03*
X1348796Y969488D03*
X1368935Y1123365D03*
X1365461Y1136100D03*
X1375463Y1142673D03*
X1364713Y1143791D03*
X1349783Y1369303D03*
X1359783D03*
X1369783D03*
X1339783D03*
X1374783D03*
X1364783D03*
X1354783D03*
X1344783D03*
X1334783D03*
X1413268Y146062D03*
X1401819Y207992D03*
X1394705Y195413D03*
X1406319Y180492D03*
X1405100Y166000D03*
X1403963Y245492D03*
X1385051Y218684D03*
X1406000Y236700D03*
X1426713Y266161D03*
X1426400Y307400D03*
X1406319Y275492D03*
Y265492D03*
X1400000Y406000D03*
X1427000Y380000D03*
X1425000Y480000D03*
X1405000D03*
Y460000D03*
X1385000Y480000D03*
X1396500Y511000D03*
X1383500Y509500D03*
X1413319Y594626D03*
X1406319Y648248D03*
Y633248D03*
Y618248D03*
X1421500Y664000D03*
X1401819Y670197D03*
X1406319Y688248D03*
X1401819Y660748D03*
Y651299D03*
X1426713Y718917D03*
X1406319Y728248D03*
Y718248D03*
Y698248D03*
X1422713Y752417D03*
X1398245Y766870D03*
X1395000Y791500D03*
X1390000Y955500D03*
X1390500Y1048000D03*
X1406319Y1071004D03*
X1413319Y1047382D03*
X1406319Y1086004D03*
Y1101004D03*
X1401819Y1104055D03*
X1385494Y1113504D03*
X1401819Y1122953D03*
X1406319Y1141004D03*
Y1151004D03*
Y1171004D03*
X1426713Y1171673D03*
X1406319Y1181004D03*
X1413319Y1219626D03*
X1422713Y1205173D03*
X1413000Y1241500D03*
X1387000Y1243500D03*
X1386500Y1258000D03*
X1418000Y1291500D03*
X1400000Y1320000D03*
X1420000D03*
X1399783Y1369303D03*
X1409783D03*
X1419783D03*
X1379783D03*
X1389783D03*
X1404783D03*
X1414783D03*
X1424783D03*
X1394783D03*
X1384783D03*
X1431713Y162661D03*
X1428013Y185956D03*
X1445994Y174086D03*
X1440300Y188000D03*
X1438186Y261287D03*
X1463000Y307000D03*
X1439300Y301500D03*
X1429800Y302500D03*
X1447170Y337890D03*
X1466500Y338100D03*
X1441770Y365790D03*
X1461100Y366000D03*
X1441970Y403990D03*
X1461300Y404200D03*
X1439500Y421500D03*
X1440000Y460000D03*
X1449576Y495482D03*
X1468605Y493549D03*
X1452279Y563600D03*
X1464700Y585600D03*
X1470000Y580000D03*
X1460274Y592498D03*
X1428013Y636417D03*
X1435413Y625417D03*
X1431713Y615417D03*
X1439713Y647917D03*
X1449000Y698000D03*
X1438087Y713756D03*
X1429213Y752417D03*
X1437213D03*
X1432000Y831000D03*
X1459500Y814000D03*
X1450500Y802500D03*
X1459500Y796500D03*
X1473000Y798000D03*
X1433500Y864500D03*
X1457500Y987500D03*
X1440000Y986500D03*
X1473008Y969646D03*
X1458967Y969535D03*
X1433500Y1044000D03*
X1456000D03*
X1435413Y1078173D03*
X1431713Y1068173D03*
X1428013Y1089173D03*
X1439713Y1100773D03*
X1438213Y1170173D03*
X1429213Y1205173D03*
X1437213D03*
X1458000Y1265500D03*
X1460000Y1300000D03*
Y1320000D03*
X1440000D03*
X1449783Y1369303D03*
X1459783D03*
X1469783D03*
X1429783D03*
X1439783D03*
X1444783D03*
X1454783D03*
X1464783D03*
X1474783D03*
X1434783D03*
X1515450Y181700D03*
X1502950D03*
X1498900Y235800D03*
X1505000Y378500D03*
X1520000Y421500D03*
X1479212Y535612D03*
X1494100Y526400D03*
X1507900Y539100D03*
X1481938Y512568D03*
X1509911Y553511D03*
X1478700Y579100D03*
X1502400Y554100D03*
X1494462Y692179D03*
X1515000Y789000D03*
X1520000Y776000D03*
X1499500Y774000D03*
Y831000D03*
X1510500Y878000D03*
X1510000Y860500D03*
X1512500Y949000D03*
X1508500Y1028500D03*
Y1050500D03*
X1488500Y1096000D03*
X1489096Y1131456D03*
X1489108Y1121674D03*
X1499675Y1142673D03*
X1489333Y1147664D03*
X1480000Y1320000D03*
X1499783Y1369303D03*
X1509783D03*
X1519783D03*
X1479783D03*
X1489783D03*
X1494783D03*
X1484783D03*
X1504783D03*
X1514783D03*
X1565555Y16517D03*
X1568030Y5500D03*
X1565555Y21517D03*
Y26517D03*
Y31517D03*
Y36517D03*
Y41517D03*
X1557000Y64500D03*
X1561500Y62000D03*
X1564000Y57500D03*
X1564555Y52124D03*
X1525336Y149369D03*
X1555925Y162661D03*
X1545383Y164116D03*
X1560000Y140000D03*
X1552225Y183661D03*
X1559625Y172661D03*
X1563925Y195261D03*
X1526031Y207992D03*
Y198543D03*
X1530531Y195492D03*
Y180492D03*
Y245492D03*
X1526031Y217441D03*
X1530142Y238021D03*
X1550925Y266161D03*
X1546925Y299661D03*
X1553425D03*
X1561425D03*
X1562425Y264661D03*
X1530531Y275492D03*
Y265492D03*
X1537531Y314114D03*
X1545000Y455000D03*
X1560000D03*
X1525000D03*
X1545000Y475000D03*
X1560000D03*
Y500000D03*
Y525000D03*
X1552000Y584500D03*
X1566000Y595000D03*
X1537531Y594626D03*
X1552225Y636417D03*
X1559625Y625417D03*
X1555925Y615417D03*
X1530531Y648248D03*
Y633248D03*
Y618248D03*
X1558925Y650017D03*
X1526031Y670197D03*
X1530531Y688248D03*
X1526031Y660748D03*
Y651299D03*
X1550925Y718917D03*
X1562425Y717417D03*
X1530531Y728248D03*
Y718248D03*
Y698248D03*
X1555000Y770000D03*
X1546925Y752417D03*
X1553425D03*
X1561425D03*
X1537531Y766870D03*
X1525000Y878000D03*
X1564500Y931000D03*
X1548500Y933000D03*
X1564000Y949000D03*
X1552500Y1028000D03*
X1557500Y1043500D03*
X1537531Y1047382D03*
X1559625Y1078173D03*
X1555925Y1068173D03*
X1530531Y1071004D03*
X1552225Y1089173D03*
X1526031Y1122953D03*
Y1113504D03*
Y1104055D03*
X1530531Y1101004D03*
Y1086004D03*
X1550925Y1171673D03*
X1552575Y1139700D03*
X1562425Y1170173D03*
X1530531Y1171004D03*
Y1151004D03*
X1528723Y1138918D03*
X1546898Y1204827D03*
X1553425Y1208897D03*
X1561425Y1205173D03*
X1537879Y1219626D03*
X1530531Y1181004D03*
X1549783Y1369303D03*
X1559783D03*
X1569783D03*
X1529783D03*
X1539783D03*
X1524783D03*
X1534783D03*
X1544783D03*
X1554783D03*
X1564783D03*
X1600000Y20000D03*
X1620000D03*
X1580000D03*
X1603030Y5500D03*
X1613030D03*
X1573030D03*
X1583030D03*
X1593030D03*
X1618030D03*
X1608030D03*
X1598030D03*
X1588030D03*
X1578030D03*
X1600000Y60000D03*
X1620000Y40000D03*
X1600000D03*
X1580000D03*
Y60000D03*
X1620000Y100000D03*
X1600000Y80000D03*
X1620000D03*
X1580000D03*
X1620000Y140000D03*
Y120000D03*
X1585757Y134147D03*
X1607000Y199000D03*
X1595500Y258500D03*
X1621100Y240561D03*
X1608000Y256000D03*
X1600000Y340000D03*
X1620000D03*
Y320000D03*
X1600000D03*
X1579500Y331000D03*
X1597245Y516662D03*
X1583030Y517405D03*
X1573000Y565500D03*
X1580000Y780000D03*
X1576500Y928500D03*
X1597221Y969572D03*
X1583180Y969461D03*
X1596000Y990000D03*
X1611500Y1078000D03*
X1593000Y1043500D03*
X1593500Y1185500D03*
X1581500Y1240000D03*
X1600000Y1320000D03*
X1614783Y1369303D03*
X1604783D03*
X1599783D03*
X1609783D03*
X1619783D03*
X1579783D03*
X1589783D03*
X1574783D03*
X1584783D03*
X1594783D03*
X1640000Y20000D03*
X1660000D03*
X1653030Y5500D03*
X1663030D03*
X1623030D03*
X1633030D03*
X1643030D03*
X1668030D03*
X1658030D03*
X1648030D03*
X1638030D03*
X1628030D03*
X1640000Y60000D03*
X1660000D03*
Y40000D03*
X1640000D03*
Y100000D03*
X1660000D03*
X1640000Y80000D03*
X1660000D03*
Y120000D03*
X1640000D03*
X1661744Y141870D03*
X1650244Y207992D03*
Y198543D03*
X1654744Y195492D03*
Y180492D03*
Y165492D03*
Y245492D03*
X1650244Y217441D03*
X1654744Y235492D03*
X1652387Y277343D03*
X1653789Y267766D03*
X1639000Y320000D03*
X1640000Y340000D03*
X1660000D03*
X1661744Y314114D03*
X1660000Y400000D03*
X1640000Y360000D03*
X1660000Y440000D03*
Y480000D03*
X1640000D03*
Y460000D03*
X1660000D03*
X1640000Y500000D03*
X1660000D03*
Y520000D03*
X1640000D03*
X1660000Y540000D03*
X1640000D03*
Y560000D03*
X1660000D03*
X1661744Y594626D03*
X1654744Y648248D03*
Y633248D03*
Y618248D03*
X1623888Y689917D03*
X1652962Y670204D03*
X1654744Y688248D03*
X1650244Y660748D03*
Y651299D03*
X1637000Y729000D03*
X1638000Y740000D03*
X1654744Y728248D03*
Y718248D03*
Y698248D03*
X1630000Y780000D03*
Y760000D03*
X1661744Y766870D03*
X1625000Y800000D03*
X1651500Y913500D03*
X1650000Y950000D03*
Y980000D03*
X1653500Y1016500D03*
X1650000Y1000000D03*
X1632000Y1049500D03*
X1654744Y1071004D03*
X1661744Y1047382D03*
X1650244Y1122953D03*
Y1113504D03*
Y1104055D03*
X1654744Y1101004D03*
Y1086004D03*
X1627563Y1132075D03*
X1627802Y1118949D03*
X1627769Y1110037D03*
X1635688Y1141158D03*
X1650841Y1168660D03*
X1654744Y1151004D03*
Y1141004D03*
X1627197Y1143044D03*
X1661744Y1219626D03*
X1668378Y1181004D03*
X1640000Y1260000D03*
X1660000D03*
X1640000Y1320000D03*
Y1300000D03*
X1660000Y1320000D03*
Y1300000D03*
Y1280000D03*
X1640000D03*
X1664783Y1369303D03*
X1654783D03*
X1644783D03*
X1634783D03*
X1624783D03*
X1649783D03*
X1659783D03*
X1629783D03*
X1639783D03*
X1700000Y20000D03*
X1680000D03*
X1703030Y5500D03*
X1713030D03*
X1673030D03*
X1683030D03*
X1693030D03*
X1718030D03*
X1708030D03*
X1698030D03*
X1688030D03*
X1678030D03*
X1700000Y60000D03*
Y40000D03*
X1680000Y60000D03*
Y40000D03*
Y100000D03*
Y80000D03*
X1700000Y100000D03*
Y80000D03*
Y140000D03*
Y120000D03*
X1680000D03*
X1679500Y144000D03*
X1680138Y162661D03*
X1676438Y183661D03*
X1683838Y172661D03*
X1688138Y195261D03*
X1675475Y267424D03*
X1671138Y299661D03*
X1677638D03*
X1685638D03*
X1686638Y264661D03*
X1678500Y320000D03*
X1700000Y400000D03*
X1680000Y380000D03*
X1700000Y360000D03*
X1680000Y440000D03*
Y420000D03*
X1700000Y440000D03*
Y420000D03*
Y460000D03*
X1680000Y480000D03*
Y460000D03*
Y500000D03*
Y520000D03*
X1700000Y540000D03*
X1680000D03*
X1707495Y517152D03*
X1700000Y560000D03*
X1680000D03*
X1676438Y636417D03*
X1683838Y625417D03*
X1680138Y615417D03*
X1688138Y648017D03*
X1675138Y718917D03*
X1686638Y717417D03*
X1710000Y770000D03*
Y785000D03*
X1685000Y770000D03*
X1671138Y752417D03*
X1677638D03*
X1685638D03*
X1709000Y915000D03*
X1687000Y905500D03*
X1716500Y943500D03*
X1706000Y1022000D03*
X1683838Y1078173D03*
X1680138Y1068173D03*
X1688138Y1100773D03*
X1676438Y1089173D03*
X1686638Y1170173D03*
X1675138Y1171673D03*
X1685638Y1205173D03*
X1677638D03*
X1671138D03*
X1680000Y1240000D03*
X1700000Y1260000D03*
X1680000D03*
X1700000Y1320000D03*
Y1300000D03*
Y1280000D03*
X1680000Y1320000D03*
Y1300000D03*
Y1280000D03*
X1714783Y1369303D03*
X1704783D03*
X1694783D03*
X1684783D03*
X1674783D03*
X1699783D03*
X1709783D03*
X1669783D03*
X1679783D03*
X1689783D03*
X1760000Y20000D03*
X1740000D03*
X1720000D03*
X1753030Y5500D03*
X1763030D03*
X1723030D03*
X1733030D03*
X1743030D03*
X1758030D03*
X1748030D03*
X1738030D03*
X1728030D03*
X1760000Y60000D03*
Y40000D03*
X1740000D03*
Y60000D03*
X1720000Y40000D03*
Y60000D03*
X1740000Y100000D03*
X1760000D03*
X1740000Y80000D03*
X1760000D03*
X1720000Y100000D03*
Y80000D03*
X1740000Y140000D03*
X1760000Y120000D03*
X1740000D03*
X1720000Y140000D03*
Y120000D03*
X1728500Y249500D03*
X1746600Y240561D03*
X1760486Y217441D03*
X1763500Y288000D03*
X1720000Y300000D03*
Y280000D03*
Y340000D03*
X1760000D03*
X1740000Y320000D03*
X1760000Y440000D03*
Y420000D03*
Y500000D03*
Y480000D03*
Y460000D03*
X1740000Y540000D03*
X1760000D03*
Y520000D03*
X1721710Y516409D03*
X1745000Y670000D03*
Y690000D03*
Y660000D03*
X1730000Y690000D03*
Y670000D03*
Y730000D03*
Y710000D03*
X1735000Y785000D03*
X1730000Y775000D03*
Y750000D03*
X1725000Y800000D03*
X1718000Y876000D03*
X1759884Y969161D03*
X1742001Y965464D03*
X1755000Y1045000D03*
X1725000D03*
X1745000Y1100000D03*
X1759055Y1113504D03*
X1736725Y1123446D03*
X1748100Y1142673D03*
X1736871Y1158178D03*
X1736941Y1141871D03*
X1728000Y1204500D03*
X1720000Y1320000D03*
X1760000D03*
X1753000Y1302000D03*
X1764783Y1369303D03*
X1754783D03*
X1744783D03*
X1734783D03*
X1724783D03*
X1749783D03*
X1759783D03*
X1719783D03*
X1729783D03*
X1739783D03*
X1778030Y5500D03*
X1793030D03*
X1803030D03*
X1813030D03*
X1808030D03*
X1798030D03*
X1783030D03*
X1788030D03*
X1773030D03*
X1768030D03*
X1780000Y60000D03*
Y40000D03*
X1800000Y100000D03*
Y80000D03*
X1780000Y100000D03*
Y80000D03*
X1800000Y120000D03*
X1780000D03*
X1785956Y141870D03*
X1804350Y162661D03*
X1801988Y183904D03*
X1808050Y172661D03*
X1812350Y195261D03*
X1774456Y207992D03*
Y198543D03*
X1778956Y195492D03*
Y180492D03*
X1775140Y165728D03*
X1778956Y245492D03*
Y235492D03*
X1799350Y266161D03*
X1795350Y299661D03*
X1801850D03*
X1809850D03*
X1810850Y264661D03*
X1778956Y275492D03*
Y265492D03*
X1785956Y314114D03*
X1800000Y440000D03*
X1780000D03*
X1800000Y500000D03*
X1780000D03*
X1800000Y480000D03*
Y460000D03*
X1780000Y480000D03*
Y460000D03*
X1800000Y540000D03*
X1780000D03*
X1800000Y520000D03*
X1780000D03*
X1800000Y560000D03*
X1785956Y594626D03*
X1800650Y636417D03*
X1808050Y625417D03*
X1804350Y615417D03*
X1812350Y648017D03*
X1778956Y648248D03*
Y633248D03*
Y618248D03*
X1774456Y670197D03*
X1778956Y688248D03*
X1774456Y660748D03*
Y651299D03*
X1799326Y717506D03*
X1811474Y717423D03*
X1778956Y728248D03*
Y718248D03*
Y698248D03*
X1766721Y716500D03*
X1795468Y752594D03*
X1801968D03*
X1809968D03*
X1785956Y766870D03*
X1773500Y879500D03*
X1771000Y944500D03*
X1799000Y945500D03*
X1788361Y964676D03*
X1799051Y963346D03*
X1785956Y1047382D03*
X1808050Y1078173D03*
X1800750Y1067973D03*
X1778956Y1071004D03*
X1800650Y1089173D03*
X1811968Y1100773D03*
X1774456Y1122953D03*
Y1104055D03*
X1778956Y1101004D03*
Y1086004D03*
X1799350Y1171673D03*
X1810850Y1170173D03*
X1778956Y1171004D03*
Y1151004D03*
Y1141004D03*
X1795350Y1205173D03*
X1801850D03*
X1809850D03*
X1785956Y1219626D03*
X1778956Y1181004D03*
X1772111Y1232695D03*
X1804783Y1369303D03*
X1794783D03*
X1784783D03*
X1774783D03*
X1799783D03*
X1809783D03*
X1769783D03*
X1779783D03*
X1789783D03*
X1843030Y5500D03*
X1853030D03*
X1863030D03*
X1838030D03*
X1858030D03*
X1848030D03*
X1823030D03*
X1833030D03*
X1828030D03*
X1818030D03*
X1860000Y60000D03*
Y80000D03*
Y100000D03*
X1840000D03*
X1820000D03*
X1860000Y140000D03*
Y120000D03*
X1840000D03*
X1820000Y140000D03*
Y120000D03*
X1856219Y212661D03*
X1841169Y254661D03*
X1840000Y340000D03*
Y320000D03*
X1860000D03*
X1820000D03*
Y440000D03*
Y480000D03*
Y460000D03*
X1840000Y540000D03*
X1820000D03*
X1845545Y516536D03*
X1831330Y517279D03*
X1840000Y580000D03*
X1820000D03*
X1840000Y560000D03*
X1820000D03*
X1862200Y686700D03*
X1856219Y665417D03*
X1850000Y745000D03*
X1837576Y707417D03*
X1820000Y780000D03*
X1857363Y1002625D03*
X1845363D03*
X1849363D03*
X1861363D03*
X1853363D03*
X1856437Y1106400D03*
X1850532Y1153286D03*
X1836231Y1140669D03*
X1860000Y1320000D03*
X1854783Y1369303D03*
X1844783D03*
X1834783D03*
X1824783D03*
X1814783D03*
X1849783D03*
X1859783D03*
X1819783D03*
X1829783D03*
X1839783D03*
X1878030Y5500D03*
X1883030D03*
X1873030D03*
X1868030D03*
X1909030D03*
X1888030D03*
X1880000Y60000D03*
X1900000D03*
X1880000Y80000D03*
X1900000D03*
Y100000D03*
X1880000D03*
X1900000Y120000D03*
X1880000Y140000D03*
Y120000D03*
X1910169Y141870D03*
X1898669Y207992D03*
Y198543D03*
X1903169Y195492D03*
Y180492D03*
Y165492D03*
X1885204Y184345D03*
X1873500Y219000D03*
X1865169Y247161D03*
Y234661D03*
X1903169Y245492D03*
X1898669Y217441D03*
X1903169Y235492D03*
X1881088Y296184D03*
X1903169Y275492D03*
Y265492D03*
X1880969Y276861D03*
X1880000Y340000D03*
Y320000D03*
X1910169Y314114D03*
X1890000Y400000D03*
Y380000D03*
Y360000D03*
Y440000D03*
Y420000D03*
X1910169Y594626D03*
X1903169Y648248D03*
Y633248D03*
Y618248D03*
X1885300Y636800D03*
X1898669Y670197D03*
X1903169Y688248D03*
X1898669Y660748D03*
Y651299D03*
X1903169Y728248D03*
Y718248D03*
Y698248D03*
X1880969Y729617D03*
X1865169Y699917D03*
X1880000Y780000D03*
X1910169Y766870D03*
X1887169Y752917D03*
X1892443Y894350D03*
X1884200Y895000D03*
X1865363Y1002625D03*
X1868100Y1055410D03*
X1903169Y1071004D03*
X1910169Y1047382D03*
X1898669Y1122953D03*
Y1113504D03*
Y1104055D03*
X1903169Y1101004D03*
Y1086004D03*
X1863131Y1133108D03*
X1903169Y1171004D03*
X1903100Y1149700D03*
X1903169Y1141004D03*
X1864352Y1153308D03*
X1871174Y1138730D03*
X1887169Y1205673D03*
X1910169Y1219626D03*
X1903169Y1181004D03*
X1880969Y1182373D03*
X1900000Y1260000D03*
Y1280000D03*
Y1320000D03*
Y1300000D03*
X1904783Y1369303D03*
X1894783D03*
X1884783D03*
X1874783D03*
X1864783D03*
X1899783D03*
X1909783D03*
X1869783D03*
X1879783D03*
X1889783D03*
X1929343Y16525D03*
Y11525D03*
Y6525D03*
X1914030Y5500D03*
X1919030D03*
X1924030D03*
X1920000Y60000D03*
X1929343Y46525D03*
Y41525D03*
Y36525D03*
Y31525D03*
Y26525D03*
Y21525D03*
Y66525D03*
Y61525D03*
Y56525D03*
Y51525D03*
X1920000Y80000D03*
Y100000D03*
X1929343Y116525D03*
Y111525D03*
Y106525D03*
Y101525D03*
Y96525D03*
Y91525D03*
Y86525D03*
Y81525D03*
Y76525D03*
Y71525D03*
X1920000Y120000D03*
X1929343Y121525D03*
Y126525D03*
Y136525D03*
Y146525D03*
Y156525D03*
Y161525D03*
Y151525D03*
Y141525D03*
Y131525D03*
Y176525D03*
Y186525D03*
Y196525D03*
Y206525D03*
Y166525D03*
Y211525D03*
Y201525D03*
Y191525D03*
Y181525D03*
Y171525D03*
Y226525D03*
Y236525D03*
Y246525D03*
Y256525D03*
Y216525D03*
Y261525D03*
Y251525D03*
Y241525D03*
Y231525D03*
Y221525D03*
Y276525D03*
Y286525D03*
Y296525D03*
Y306525D03*
Y266525D03*
Y301525D03*
Y291525D03*
Y281525D03*
Y271525D03*
Y326525D03*
Y336525D03*
Y346525D03*
Y356525D03*
Y316525D03*
Y351525D03*
Y341525D03*
Y331525D03*
Y321525D03*
Y311525D03*
Y376525D03*
Y386525D03*
Y396525D03*
Y406525D03*
Y366525D03*
Y401525D03*
Y391525D03*
Y381525D03*
Y371525D03*
Y361525D03*
Y426525D03*
Y436525D03*
Y446525D03*
Y416525D03*
Y451525D03*
Y441525D03*
Y431525D03*
Y421525D03*
Y411525D03*
Y476525D03*
Y486525D03*
Y496525D03*
Y456525D03*
Y466525D03*
Y501525D03*
Y491525D03*
Y481525D03*
Y471525D03*
Y461525D03*
Y526525D03*
Y536525D03*
Y546525D03*
Y506525D03*
Y516525D03*
Y551525D03*
Y541525D03*
Y531525D03*
Y521525D03*
Y511525D03*
Y576525D03*
Y586525D03*
Y596525D03*
Y556525D03*
Y566525D03*
Y591525D03*
Y581525D03*
Y571525D03*
Y561525D03*
Y626525D03*
Y636525D03*
Y646525D03*
Y606525D03*
Y616525D03*
Y641525D03*
Y631525D03*
Y621525D03*
Y611525D03*
Y601525D03*
Y676525D03*
Y686525D03*
Y696525D03*
Y656525D03*
Y666525D03*
Y691525D03*
Y681525D03*
Y671525D03*
Y661525D03*
Y651525D03*
Y726525D03*
Y736525D03*
Y706525D03*
Y716525D03*
Y741525D03*
Y731525D03*
Y721525D03*
Y711525D03*
Y701525D03*
Y776525D03*
Y786525D03*
Y746525D03*
Y756525D03*
Y766525D03*
Y791525D03*
Y781525D03*
Y771525D03*
Y761525D03*
Y751525D03*
Y826525D03*
Y836525D03*
Y796525D03*
Y806525D03*
Y816525D03*
Y841525D03*
Y831525D03*
Y821525D03*
Y811525D03*
Y801525D03*
Y876525D03*
Y886525D03*
Y846525D03*
Y856525D03*
Y866525D03*
Y881525D03*
Y871525D03*
Y861525D03*
Y851525D03*
Y926525D03*
Y896525D03*
Y906525D03*
Y916525D03*
Y931525D03*
Y921525D03*
Y911525D03*
Y901525D03*
Y891525D03*
Y936525D03*
Y973863D03*
Y978863D03*
Y983863D03*
Y951525D03*
Y956525D03*
Y961525D03*
Y966525D03*
Y946525D03*
Y941525D03*
Y988863D03*
Y993863D03*
Y998863D03*
Y1003863D03*
Y1008863D03*
Y1033863D03*
Y1028863D03*
Y1023863D03*
Y1018863D03*
Y1013863D03*
Y1073863D03*
Y1083863D03*
Y1043863D03*
Y1053863D03*
Y1063863D03*
Y1078863D03*
Y1068863D03*
Y1058863D03*
Y1048863D03*
Y1038863D03*
Y1123863D03*
Y1093863D03*
Y1103863D03*
Y1113863D03*
Y1128863D03*
Y1118863D03*
Y1108863D03*
Y1098863D03*
Y1088863D03*
Y1173863D03*
Y1133863D03*
Y1143863D03*
Y1153863D03*
Y1163863D03*
Y1178863D03*
Y1168863D03*
Y1158863D03*
Y1148863D03*
Y1138863D03*
Y1223863D03*
Y1183863D03*
Y1193863D03*
Y1203863D03*
Y1213863D03*
Y1228863D03*
Y1218863D03*
Y1208863D03*
Y1198863D03*
Y1188863D03*
X1920000Y1260000D03*
X1929343Y1273863D03*
Y1233863D03*
Y1243863D03*
Y1253863D03*
Y1263863D03*
Y1268863D03*
Y1258863D03*
Y1248863D03*
Y1238863D03*
X1920000Y1280000D03*
Y1320000D03*
Y1300000D03*
X1929343Y1323863D03*
Y1283863D03*
Y1293863D03*
Y1303863D03*
Y1313863D03*
Y1318863D03*
Y1308863D03*
Y1298863D03*
Y1288863D03*
Y1278863D03*
Y1333863D03*
Y1343863D03*
Y1353863D03*
X1924783Y1369303D03*
X1914783D03*
X1919783D03*
X1929343Y1358863D03*
Y1348863D03*
Y1338863D03*
Y1328863D03*
Y1363863D03*
G54D28*
X188706Y941328D03*
X194206D03*
X260703Y529168D03*
X255203D03*
X702483Y945989D03*
X730882Y888502D03*
X716233Y868219D03*
X733422Y857828D03*
X721552Y951317D03*
X725852Y951067D03*
X763883Y907689D03*
X755883D03*
X750883Y903689D03*
X802102Y51075D03*
X799102Y48575D03*
X802102Y46075D03*
X799102Y43575D03*
X802102Y41075D03*
X868100Y685600D03*
X871700D03*
X875300D03*
X884600Y688800D03*
X881000D03*
X877400D03*
X891000Y743500D03*
X870500Y762500D03*
X932294Y1379995D03*
X928194D03*
X1843731Y936066D03*
X1843811Y940067D03*
X1830665Y941751D03*
X1836165D03*
X1908107Y831894D03*
X1902607D03*
X1907999Y846368D03*
X1902499D03*
G54D23*
X111800Y987200D03*
Y983200D03*
X115800Y979200D03*
X119800Y971200D03*
Y975200D03*
Y979200D03*
X115800Y975200D03*
X119800Y987200D03*
Y983200D03*
X115800Y971200D03*
Y983200D03*
Y987200D03*
X119163Y959625D03*
X121914Y1003491D03*
X153263Y568725D03*
X146263D03*
X144263Y573225D03*
X138763Y568725D03*
X148763Y576225D03*
X188614Y591491D03*
X182500Y559200D03*
Y571200D03*
Y575200D03*
X178500D03*
Y571200D03*
X182500Y567200D03*
X186500Y559200D03*
Y563200D03*
Y567200D03*
X182500Y563200D03*
X186500Y575200D03*
Y571200D03*
X184017Y951112D03*
Y945612D03*
X198463Y945525D03*
Y951025D03*
X265392Y539225D03*
Y533725D03*
X250586Y533920D03*
Y539420D03*
X465346Y1122953D03*
X858632Y399200D03*
X855032D03*
Y395600D03*
X858632D03*
X855032Y392000D03*
X858632D03*
X852832Y406400D03*
Y402800D03*
X856432Y406400D03*
Y402800D03*
X852832Y410000D03*
X856432D03*
X1398493Y314114D03*
X1717681Y1006054D03*
X1712181Y1001554D03*
X1757600Y987200D03*
X1761600D03*
Y983200D03*
X1757600D03*
X1761600Y991200D03*
Y999200D03*
Y995200D03*
X1757600Y991200D03*
X1753600Y995200D03*
Y999200D03*
X1757600D03*
Y995200D03*
X1726681Y1001554D03*
X1719681D03*
X1722181Y1009054D03*
X1763714Y1015491D03*
X1840419Y945557D03*
Y951057D03*
X1825945Y945449D03*
Y950949D03*
G54D37*
X944882Y-63877D03*
G54D39*
X942126Y58465D03*
Y346457D03*
Y437598D03*
Y725590D03*
X1110236Y58465D03*
Y346457D03*
Y437598D03*
Y725590D03*
G54D34*
X496653Y80906D03*
X1465157D03*
G54D15*
X60540Y-85109D03*
X59536Y1573374D03*
X79000Y1301900D03*
X1826700Y77600D03*
X1865705Y1573374D03*
X1898432Y-93682D03*
X1908500Y1346800D03*
G54D12*
X15157Y474409D03*
X904921Y-25591D03*
X1894684Y474409D03*
G54D18*
X80019Y51968D03*
X127263Y20472D03*
X631200Y51968D03*
X678444Y20472D03*
X1250689Y51969D03*
X1297933Y20472D03*
X1801870Y51969D03*
X1849114Y20472D03*
G54D10*
X15157Y21653D03*
X904921Y564960D03*
X1894685Y21654D03*
G54D35*
X496653Y110552D03*
X1465157D03*
G54D26*
X173228Y1062992D03*
X421653Y1141732D03*
X670079Y1062992D03*
X1343701D03*
X1592126Y1141732D03*
X1840551Y1062992D03*
G54D36*
X503248Y829921D03*
X1673917D03*
G54D13*
X31496Y882677D03*
X168307Y646457D03*
X660236D03*
X718110Y820866D03*
X1366142Y646457D03*
X1462992Y866929D03*
X1602756Y646457D03*
X1903346Y803937D03*
G54D40*
X975787Y-25590D03*
G54D17*
X103642Y36220D03*
X654822D03*
X1274311D03*
X1825492D03*
G54D27*
X173228Y1114173D03*
X670079D03*
X1343700D03*
X1840551D03*
G54D41*
X975786Y564960D03*
G54D45*
X1104527Y1630792D03*
G54D16*
X47000Y1107500D03*
X549279Y513331D03*
X525579Y538331D03*
X557279Y513331D03*
X533879Y566031D03*
X548767Y556819D03*
X520579Y553231D03*
X517499Y576931D03*
X575700Y528831D03*
X563279Y506731D03*
X704399Y626799D03*
Y618399D03*
Y622599D03*
X748500Y1287500D03*
X752000Y1197500D03*
X756000Y1225500D03*
X770000Y1231500D03*
X769500Y1283500D03*
X827000Y1168000D03*
X802500Y1194500D03*
X807500D03*
X812500D03*
X810000Y1191500D03*
X805000D03*
X870163Y836153D03*
X865663Y834403D03*
X895869Y932822D03*
X898920Y1020000D03*
X906000Y1222000D03*
X924500Y1236000D03*
X932500Y1493200D03*
X926500Y1499700D03*
X918500D03*
X906000Y1543700D03*
X962900Y905000D03*
X953967Y933635D03*
X948942Y974655D03*
X961134Y976191D03*
X946138Y1006299D03*
X944921Y1515200D03*
X986614Y1619764D03*
X974016D03*
Y1597126D03*
X986614D03*
X974016Y1591220D03*
Y1603031D03*
Y1613858D03*
X986614Y1591220D03*
Y1613858D03*
Y1603031D03*
X974016Y1625669D03*
X986614D03*
X1031563Y852453D03*
X1025774Y1001538D03*
X992994Y1005740D03*
X1037000Y1067100D03*
X1032500D03*
X1017000Y1093950D03*
X1021200Y1094300D03*
X1002362Y1597126D03*
X1014961D03*
X1030709D03*
X1002362Y1591220D03*
Y1603031D03*
X1014961Y1591220D03*
Y1603031D03*
X1030709Y1591220D03*
Y1603031D03*
X1076000Y-10500D03*
X1062854Y83434D03*
X1053200Y901703D03*
X1043882Y901568D03*
X1082500Y1067100D03*
X1073500D03*
X1064500Y1096150D03*
X1068700Y1096600D03*
X1066750Y1224035D03*
X1079250D03*
X1066750Y1209862D03*
X1079250D03*
X1066750Y1216949D03*
X1079250D03*
X1066750Y1231122D03*
X1079250D03*
X1066750Y1238209D03*
X1079250D03*
X1066750Y1245295D03*
X1079250D03*
X1066750Y1301988D03*
X1079250D03*
X1066750Y1309075D03*
X1079250D03*
X1066750Y1316161D03*
X1079250D03*
X1066750Y1323248D03*
X1079250D03*
X1066750Y1294902D03*
X1079250D03*
X1066750Y1330335D03*
X1079250D03*
X1066750Y1387028D03*
X1079250D03*
X1066750Y1394114D03*
X1079250D03*
X1066750Y1401201D03*
X1079250D03*
X1066750Y1408287D03*
X1079250D03*
X1066750Y1415374D03*
X1079250D03*
X1066750Y1379941D03*
X1079250D03*
X1043307Y1597126D03*
Y1591220D03*
Y1603031D03*
X1100847Y905617D03*
X1105847D03*
X1110847D03*
X1108347Y902617D03*
X1103347D03*
X1119700Y1067200D03*
X1124500D03*
X1101580Y1091120D03*
X1107100Y1096050D03*
X1111600Y1097800D03*
X1090818Y1531620D03*
X1092927Y1558887D03*
Y1555087D03*
X1095938Y1531620D03*
Y1535420D03*
X1090818D03*
X1096547Y1558887D03*
Y1555087D03*
X1265250Y167823D03*
X1252750D03*
X1376963D03*
X1355700Y587600D03*
X1359700D03*
X1389463Y167823D03*
G54D25*
X127988Y194242D03*
Y181742D03*
Y634498D03*
Y646998D03*
Y1087254D03*
Y1099754D03*
X252200Y194242D03*
Y181742D03*
Y634498D03*
Y646998D03*
Y1087254D03*
Y1099754D03*
X322545Y72845D03*
X376413Y194242D03*
Y181742D03*
Y634498D03*
Y646998D03*
Y1087254D03*
Y1099754D03*
X453473Y1089300D03*
X500625Y194242D03*
Y181742D03*
Y634498D03*
Y646998D03*
X460673Y1071976D03*
X460873Y1077526D03*
X500625Y1087254D03*
Y1099754D03*
X624838Y194242D03*
Y181742D03*
Y634498D03*
Y646998D03*
Y1087254D03*
Y1099754D03*
X696787Y580633D03*
X749051Y194242D03*
Y181742D03*
Y634498D03*
Y646998D03*
X708683Y876958D03*
X749051Y1087254D03*
Y1099754D03*
X928600Y-115200D03*
X986713Y-115570D03*
X971713D03*
X1046713D03*
X1076713D03*
X1117535Y-115157D03*
X1091089Y988592D03*
X1105262D03*
X1119435D03*
X1133609D03*
X1095026Y995678D03*
X1109199D03*
X1123372D03*
X1091089Y1002765D03*
X1105262D03*
X1119435D03*
X1133609D03*
X1095026Y1009852D03*
X1109199D03*
X1123372D03*
X1091089Y1016938D03*
X1105262D03*
X1119435D03*
X1133609D03*
X1095026Y1024025D03*
X1109199D03*
X1123372D03*
X1091089Y1031111D03*
X1105262D03*
X1119435D03*
X1133609D03*
X1095026Y1038198D03*
X1109199D03*
X1123372D03*
X1091089Y1160257D03*
Y1174430D03*
X1105262Y1160257D03*
Y1174430D03*
X1119435Y1160257D03*
Y1174430D03*
X1133609Y1160257D03*
Y1174430D03*
X1095026Y1167343D03*
X1109199D03*
X1123372D03*
X1091089Y1188603D03*
Y1202776D03*
Y1216949D03*
X1105262Y1188603D03*
Y1202776D03*
Y1216949D03*
X1119435Y1188603D03*
Y1202776D03*
Y1216949D03*
X1133609Y1188603D03*
Y1202776D03*
Y1216949D03*
X1095026Y1181516D03*
Y1195690D03*
Y1209863D03*
Y1224036D03*
X1109199Y1181516D03*
Y1195690D03*
Y1209863D03*
Y1224036D03*
X1123372Y1181516D03*
Y1195690D03*
Y1209863D03*
Y1224036D03*
X1091089Y1231123D03*
Y1245296D03*
Y1259469D03*
Y1273642D03*
X1105262Y1231123D03*
Y1245296D03*
Y1259469D03*
Y1273642D03*
X1119435Y1231123D03*
Y1245296D03*
Y1259469D03*
Y1273642D03*
X1133609Y1231123D03*
Y1245296D03*
Y1259469D03*
Y1273642D03*
X1095026Y1238209D03*
Y1252382D03*
Y1266556D03*
X1109199Y1238209D03*
Y1252382D03*
Y1266556D03*
X1123372Y1238209D03*
Y1252382D03*
Y1266556D03*
X1091089Y1287816D03*
Y1301989D03*
Y1316162D03*
X1105262Y1287816D03*
Y1301989D03*
Y1316162D03*
X1119435Y1287816D03*
Y1301989D03*
Y1316162D03*
X1133609Y1287816D03*
Y1301989D03*
Y1316162D03*
X1095026Y1280729D03*
Y1294902D03*
Y1309075D03*
Y1323249D03*
X1109199Y1280729D03*
Y1294902D03*
Y1309075D03*
Y1323249D03*
X1123372Y1280729D03*
Y1294902D03*
Y1309075D03*
Y1323249D03*
X1091089Y1330335D03*
Y1344508D03*
Y1358682D03*
Y1372855D03*
X1105262Y1330335D03*
Y1344508D03*
Y1358682D03*
Y1372855D03*
X1119435Y1330335D03*
Y1344508D03*
Y1358682D03*
Y1372855D03*
X1133609Y1330335D03*
Y1344508D03*
Y1358682D03*
Y1372855D03*
X1095026Y1337422D03*
Y1351595D03*
Y1365768D03*
X1109199Y1337422D03*
Y1351595D03*
Y1365768D03*
X1123372Y1337422D03*
Y1351595D03*
Y1365768D03*
X1091089Y1387028D03*
Y1401201D03*
X1105262Y1387028D03*
Y1401201D03*
X1119435Y1387028D03*
Y1401201D03*
X1133609Y1387028D03*
Y1401201D03*
X1095026Y1379942D03*
Y1394115D03*
Y1408288D03*
X1109199Y1379942D03*
Y1394115D03*
Y1408288D03*
X1123372Y1379942D03*
Y1394115D03*
Y1408288D03*
X1101457Y1588583D03*
X1119685D03*
X1108150D03*
X1126378D03*
X1182590Y254388D03*
X1174037Y281343D03*
X1278500Y634498D03*
Y646998D03*
Y1087254D03*
Y1099754D03*
X1402713Y181742D03*
Y194242D03*
Y634498D03*
Y646998D03*
Y1087254D03*
Y1099754D03*
X1526925Y181742D03*
Y194242D03*
Y634498D03*
Y646998D03*
Y1087254D03*
Y1099754D03*
X1651138Y181742D03*
Y194242D03*
Y634498D03*
Y646998D03*
Y1087254D03*
Y1099754D03*
X1725350Y634498D03*
Y646998D03*
X1775350Y181742D03*
Y194242D03*
Y1087254D03*
Y1099754D03*
X1859017Y161725D03*
X1859117Y167375D03*
X1851717Y179075D03*
X1858917Y614481D03*
X1859117Y620131D03*
X1851717Y635331D03*
X1848491Y819787D03*
Y823787D03*
Y815787D03*
Y807787D03*
Y811787D03*
X1899563Y181742D03*
Y194242D03*
Y634498D03*
Y646998D03*
X1871000Y1073300D03*
X1899563Y1087254D03*
Y1099754D03*
X1863700Y1085000D03*
G54D29*
X184295Y1009469D03*
Y1014969D03*
X198741Y1014882D03*
Y1009382D03*
X265275Y596896D03*
X250974Y597308D03*
X265275Y602396D03*
X250974Y602808D03*
X429724Y63977D03*
X443898D03*
X458071D03*
X436811Y67914D03*
X450984D03*
X429724Y92323D03*
Y106496D03*
Y78150D03*
X436811Y82087D03*
X450984D03*
X443898Y92323D03*
X458071D03*
X436811Y96260D03*
X450984D03*
X443898Y106496D03*
X458071D03*
X436811Y110433D03*
X450984D03*
X443898Y78150D03*
X458071D03*
X429724Y120670D03*
X443898D03*
X458071D03*
X465157Y67914D03*
X472244Y63977D03*
X479331Y67914D03*
X465157Y82087D03*
Y96260D03*
Y110433D03*
X479331Y82087D03*
X472244Y92323D03*
X479331Y96260D03*
X472244Y106496D03*
X479331Y110433D03*
X472244Y78150D03*
Y120670D03*
X514764Y63977D03*
X550197Y67914D03*
X536024D03*
X521850D03*
X543110Y63977D03*
X528937D03*
X557283D03*
X514764Y106496D03*
Y92323D03*
Y78150D03*
X550197Y110433D03*
X536024D03*
X521850D03*
X543110Y106496D03*
X528937D03*
X550197Y96260D03*
X536024D03*
X521850D03*
X543110Y92323D03*
X528937D03*
X550197Y82087D03*
X536024D03*
X521850D03*
X543110Y78150D03*
X528937D03*
X557283Y106496D03*
Y92323D03*
Y78150D03*
X514764Y120670D03*
X543110D03*
X528937D03*
X557283D03*
X564370Y67914D03*
Y110433D03*
Y96260D03*
Y82087D03*
X1398228Y63977D03*
X1412402D03*
X1426575D03*
X1405315Y67914D03*
X1419488D03*
X1398228Y92323D03*
Y106496D03*
Y78150D03*
X1405315Y82087D03*
X1419488D03*
X1412402Y92323D03*
X1426575D03*
X1405315Y96260D03*
X1419488D03*
X1412402Y106496D03*
X1426575D03*
X1405315Y110433D03*
X1419488D03*
X1412402Y78150D03*
X1426575D03*
X1398228Y120670D03*
X1412402D03*
X1426575D03*
X1433661Y67914D03*
X1440748Y63977D03*
X1447835Y67914D03*
X1433661Y82087D03*
Y96260D03*
Y110433D03*
X1447835Y82087D03*
X1440748Y92323D03*
X1447835Y96260D03*
X1440748Y106496D03*
X1447835Y110433D03*
X1440748Y78150D03*
Y120670D03*
X1483268Y63977D03*
X1518701Y67914D03*
X1504528D03*
X1490354D03*
X1511614Y63977D03*
X1497441D03*
X1483268Y106496D03*
Y92323D03*
Y78150D03*
X1518701Y110433D03*
X1504528D03*
X1490354D03*
X1511614Y106496D03*
X1497441D03*
X1518701Y96260D03*
X1504528D03*
X1490354D03*
X1511614Y92323D03*
X1497441D03*
X1518701Y82087D03*
X1504528D03*
X1490354D03*
X1511614Y78150D03*
X1497441D03*
X1483268Y120670D03*
X1511614D03*
X1497441D03*
X1532874Y67914D03*
X1525787Y63977D03*
X1532874Y110433D03*
X1525787Y106496D03*
X1532874Y96260D03*
X1525787Y92323D03*
X1532874Y82087D03*
X1525787Y78150D03*
Y120670D03*
X1825971Y1015512D03*
Y1010012D03*
X1840445Y1015620D03*
Y1010120D03*
X1912551Y836444D03*
Y841944D03*
G54D30*
X188552Y1019166D03*
X194052D03*
X255410Y607833D03*
X260910D03*
X1850151Y835119D03*
X1850177Y838746D03*
X1838239Y831626D03*
X1845579Y831731D03*
X1838311Y827911D03*
X1845651Y828016D03*
X1860276Y916059D03*
Y912059D03*
X1835895Y1020064D03*
X1830395D03*
X1872276Y916059D03*
X1876276D03*
Y920059D03*
X1872276D03*
X1868276Y916059D03*
X1864276Y912059D03*
X1868276D03*
X1864276Y916059D03*
X1876276Y912059D03*
X1872276D03*
X1875801Y946796D03*
X1875769Y951122D03*
X1880122Y954062D03*
X1880383Y950341D03*
G36*
G01X149668Y380135D02*
G02X112735I-18466J-14781D01*
G03X119308Y392599I-29176J23351D01*
G02X143095I11894J-3623D01*
G03X149668Y380135I35749J10887D01*
G37*
G36*
G01X149667Y832891D02*
G02X112734I-18466J-14781D01*
G03X119307Y845355I-29176J23351D01*
G02X143094I11894J-3623D01*
G03X149667Y832891I35749J10887D01*
G37*
G36*
G01X149668Y1285647D02*
G02X112735I-18466J-14781D01*
G03X119308Y1298111I-29176J23351D01*
G02X143095I11894J-3623D01*
G03X149668Y1285647I35749J10887D01*
G37*
G36*
G01X397699Y380135D02*
G02X360766I-18467J-14781D01*
G03X367339Y392599I-29176J23351D01*
G02X391126I11894J-3623D01*
G03X397699Y380135I35749J10887D01*
G37*
G36*
G01Y832891D02*
G02X360766I-18467J-14781D01*
G03X367339Y845355I-29176J23351D01*
G02X391126I11894J-3623D01*
G03X397699Y832891I35749J10887D01*
G37*
G36*
G01Y1285647D02*
G02X360766I-18467J-14781D01*
G03X367339Y1298111I-29176J23351D01*
G02X391126I11894J-3623D01*
G03X397699Y1285647I35749J10887D01*
G37*
G36*
G01X645730Y380135D02*
G02X608797I-18466J-14781D01*
G03X615370Y392599I-29176J23351D01*
G02X639157I11893J-3623D01*
G03X645730Y380135I35749J10887D01*
G37*
G36*
G01Y832891D02*
G02X608797I-18466J-14781D01*
G03X615370Y845355I-29176J23351D01*
G02X639157I11893J-3623D01*
G03X645730Y832891I35749J10887D01*
G37*
G36*
G01Y1285647D02*
G02X608797I-18466J-14781D01*
G03X615370Y1298111I-29176J23351D01*
G02X639157I11893J-3623D01*
G03X645730Y1285647I35749J10887D01*
G37*
G36*
G01X814924Y265984D02*
G02X777991I-18467J-14781D01*
G03X784564Y278448I-29176J23351D01*
G02X808351I11893J-3623D01*
G03X814924Y265984I35749J10887D01*
G37*
G36*
G01Y738425D02*
G02X777991I-18467J-14781D01*
G03X784564Y750889I-29176J23351D01*
G02X808351I11893J-3623D01*
G03X814924Y738425I35749J10887D01*
G37*
G36*
G01X979885Y1090394D02*
G02X942952I-18467J-14781D01*
G03X949525Y1102858I-29176J23351D01*
G02X973312I11894J-3623D01*
G03X979885Y1090394I35749J10887D01*
G37*
G36*
G01Y1432913D02*
G02X942952I-18467J-14781D01*
G03X949525Y1445377I-29176J23351D01*
G02X973312I11894J-3623D01*
G03X979885Y1432913I35749J10887D01*
G37*
G36*
G01X1200357Y558898D02*
G02X1163424I-18467J-14781D01*
G03X1169997Y571362I-29176J23351D01*
G02X1193784I11894J-3623D01*
G03X1200357Y558898I35749J10887D01*
G37*
G36*
G01X1200337Y972261D02*
G02X1163404I-18467J-14781D01*
G03X1169977Y984725I-29176J23351D01*
G02X1193764I11894J-3623D01*
G03X1200337Y972261I35749J10887D01*
G37*
G36*
G01X1200357Y1562835D02*
G02X1163424I-18467J-14781D01*
G03X1169997Y1575299I-29176J23351D01*
G02X1193784I11894J-3623D01*
G03X1200357Y1562835I35749J10887D01*
G37*
G36*
G01X1320337Y380135D02*
G02X1283404I-18467J-14781D01*
G03X1289977Y392599I-29176J23351D01*
G02X1313764I11894J-3623D01*
G03X1320337Y380135I35749J10887D01*
G37*
G36*
G01Y832891D02*
G02X1283404I-18467J-14781D01*
G03X1289977Y845355I-29176J23351D01*
G02X1313764I11894J-3623D01*
G03X1320337Y832891I35749J10887D01*
G37*
G36*
G01Y1285647D02*
G02X1283404I-18467J-14781D01*
G03X1289977Y1298111I-29176J23351D01*
G02X1313764I11894J-3623D01*
G03X1320337Y1285647I35749J10887D01*
G37*
G36*
G01X1568368Y380135D02*
G02X1531435I-18467J-14781D01*
G03X1538008Y392599I-29176J23351D01*
G02X1561795I11894J-3623D01*
G03X1568368Y380135I35749J10887D01*
G37*
G36*
G01Y832891D02*
G02X1531435I-18467J-14781D01*
G03X1538008Y845355I-29176J23351D01*
G02X1561795I11894J-3623D01*
G03X1568368Y832891I35749J10887D01*
G37*
G36*
G01Y1285647D02*
G02X1531435I-18467J-14781D01*
G03X1538008Y1298111I-29176J23351D01*
G02X1561795I11894J-3623D01*
G03X1568368Y1285647I35749J10887D01*
G37*
G36*
G01X1816400Y380135D02*
G02X1779467I-18466J-14781D01*
G03X1786040Y392599I-29176J23351D01*
G02X1809827I11894J-3623D01*
G03X1816400Y380135I35749J10887D01*
G37*
G36*
G01Y832891D02*
G02X1779467I-18466J-14781D01*
G03X1786040Y845355I-29176J23351D01*
G02X1809827I11894J-3623D01*
G03X1816400Y832891I35749J10887D01*
G37*
G36*
G01Y1285647D02*
G02X1779467I-18466J-14781D01*
G03X1786040Y1298111I-29176J23351D01*
G02X1809827I11894J-3623D01*
G03X1816400Y1285647I35749J10887D01*
G37*
%LPC*%
G75*
G54D46*
G01X363248Y-425196D02*
Y-505196D01*
G01D02*
X1639148D01*
G01X359248Y-409196D02*
G02I-12000J0D01*
G01X354098D02*
G02I-6850J0D01*
G01X347248Y-425196D02*
Y-393196D01*
G01X363248Y-425196D02*
X1639148D01*
G01X363248Y-460696D02*
X1639148D01*
G01X363248Y-409196D02*
X331248D01*
G01X720748Y-425196D02*
Y-505196D01*
G01X858248Y-425196D02*
Y-505196D01*
G01X973248Y-425196D02*
Y-505196D01*
G01X1271648Y-425196D02*
Y-505196D01*
G01X1441648Y-425196D02*
Y-505196D01*
G01X1639148Y-425196D02*
Y-505196D01*
G01X1667148Y-409196D02*
G02I-12000J0D01*
G01X1661998D02*
G02I-6850J0D01*
G01X1655148Y-425196D02*
Y-393196D01*
G01X1671148Y-409196D02*
X1639148D01*
G54D47*
G01X394744Y-485863D02*
X395618Y-484988D01*
X396273Y-483530D01*
X396710Y-481487D01*
X396273Y-479738D01*
X395400Y-478571D01*
X393871Y-477696D01*
X387976D01*
Y-495196D01*
X395181D01*
X396710Y-494030D01*
X397583Y-492279D01*
X398020Y-490238D01*
X397583Y-488196D01*
X396273Y-486446D01*
X394744Y-485863D01*
X387976D01*
G01X407441Y-495196D02*
Y-483530D01*
G01Y-485863D02*
X408533Y-484696D01*
X409625Y-483821D01*
X411153Y-483530D01*
X412244Y-483821D01*
X413555Y-484696D01*
G01X423413Y-500446D02*
X424723Y-501029D01*
X426470Y-500446D01*
X427561Y-499280D01*
X428435Y-497821D01*
X429744Y-493155D01*
X432583Y-483530D01*
G01X425596D02*
X429744Y-493155D01*
G01X448991Y-484988D02*
X447463Y-483821D01*
X446153Y-483530D01*
X444406Y-484113D01*
X443096Y-485279D01*
X442223Y-487321D01*
X442004Y-489363D01*
X442223Y-491405D01*
X443096Y-493155D01*
X444406Y-494613D01*
X446153Y-495196D01*
X447681Y-494613D01*
X448991Y-493446D01*
G01X459723Y-487321D02*
X466710D01*
X466055Y-485279D01*
X464963Y-484113D01*
X463435Y-483530D01*
X461906Y-483821D01*
X460596Y-484696D01*
X459723Y-486738D01*
X459286Y-488488D01*
Y-490238D01*
X459723Y-491988D01*
X460815Y-493738D01*
X462125Y-494904D01*
X463653Y-495196D01*
X465181Y-494613D01*
X466710Y-492863D01*
G01X502801Y-479155D02*
X501491Y-478279D01*
X499963Y-477696D01*
X498216D01*
X496251Y-478571D01*
X494723Y-480029D01*
X493631Y-481780D01*
X492758Y-484696D01*
X492539Y-487321D01*
X492976Y-489946D01*
X493631Y-491696D01*
X494941Y-493446D01*
X496470Y-494613D01*
X497998Y-495196D01*
X499526D01*
X501055Y-494613D01*
X502365Y-493738D01*
X503457Y-492572D01*
G01X519428Y-495196D02*
Y-483530D01*
G01Y-485571D02*
X518555Y-484405D01*
X517244Y-483821D01*
X515716Y-483530D01*
X514188Y-484113D01*
X512878Y-485279D01*
X512004Y-487029D01*
X511568Y-489363D01*
X512004Y-491696D01*
X512878Y-493446D01*
X514188Y-494613D01*
X515716Y-495196D01*
X517244Y-494904D01*
X518555Y-494030D01*
X519428Y-492863D01*
G01X529286Y-495196D02*
Y-483530D01*
G01Y-486446D02*
X530160Y-484988D01*
X531470Y-483821D01*
X533216Y-483530D01*
X534744Y-483821D01*
X536055Y-484988D01*
X536710Y-487029D01*
Y-495196D01*
G01X545913Y-500446D02*
X547223Y-501029D01*
X548970Y-500446D01*
X550061Y-499280D01*
X550935Y-497821D01*
X552244Y-493155D01*
X555083Y-483530D01*
G01X548096D02*
X552244Y-493155D01*
G01X567998Y-495196D02*
X566688Y-494904D01*
X565378Y-493738D01*
X564504Y-491696D01*
X564068Y-489363D01*
X564504Y-487029D01*
X565378Y-484988D01*
X566688Y-483821D01*
X567998Y-483530D01*
X569308Y-483821D01*
X570618Y-484988D01*
X571491Y-487029D01*
X571710Y-489363D01*
X571491Y-491696D01*
X570618Y-493738D01*
X569308Y-494904D01*
X567998Y-495196D01*
G01X581786D02*
Y-483530D01*
G01Y-486446D02*
X582660Y-484988D01*
X583970Y-483821D01*
X585716Y-483530D01*
X587244Y-483821D01*
X588555Y-484988D01*
X589210Y-487029D01*
Y-495196D01*
G01X616350D02*
Y-477696D01*
X624646D01*
G01X621590Y-486154D02*
X616350D01*
G01X637998Y-495779D02*
X637561Y-495488D01*
Y-494904D01*
X637998Y-494613D01*
X638435Y-494904D01*
Y-495488D01*
X637998Y-495779D01*
G01X650695Y-495196D02*
Y-477696D01*
X655061D01*
X656808Y-478571D01*
X658118Y-479738D01*
X659210Y-481487D01*
X660083Y-483530D01*
X660301Y-486446D01*
X660083Y-489363D01*
X659210Y-491405D01*
X658118Y-493155D01*
X656808Y-494321D01*
X655061Y-495196D01*
X650695D01*
G01X668631D02*
Y-477696D01*
X673871D01*
X675618Y-478571D01*
X676928Y-480613D01*
X677365Y-482946D01*
X676928Y-485279D01*
X675836Y-487029D01*
X673871Y-487905D01*
X668631D01*
G01X692244Y-485863D02*
X693118Y-484988D01*
X693773Y-483530D01*
X694210Y-481487D01*
X693773Y-479738D01*
X692900Y-478571D01*
X691371Y-477696D01*
X685476D01*
Y-495196D01*
X692681D01*
X694210Y-494030D01*
X695083Y-492279D01*
X695520Y-490238D01*
X695083Y-488196D01*
X693773Y-486446D01*
X692244Y-485863D01*
X685476D01*
G01X501071Y-450196D02*
Y-432696D01*
X506748Y-447279D01*
X512425Y-432696D01*
Y-450196D01*
G01X524248D02*
X522938Y-449904D01*
X521628Y-448738D01*
X520754Y-446696D01*
X520318Y-444363D01*
X520754Y-442029D01*
X521628Y-439988D01*
X522938Y-438821D01*
X524248Y-438530D01*
X525558Y-438821D01*
X526868Y-439988D01*
X527741Y-442029D01*
X527960Y-444363D01*
X527741Y-446696D01*
X526868Y-448738D01*
X525558Y-449904D01*
X524248Y-450196D01*
G01X545678Y-432696D02*
Y-450196D01*
G01Y-447572D02*
X544805Y-449030D01*
X543494Y-449904D01*
X541966Y-450196D01*
X540220Y-449613D01*
X538910Y-448155D01*
X538036Y-446405D01*
X537818Y-444363D01*
X538036Y-442321D01*
X538910Y-440571D01*
X540220Y-439113D01*
X541966Y-438530D01*
X543494Y-438821D01*
X544586Y-439405D01*
X545678Y-440571D01*
G01X555973Y-442321D02*
X562960D01*
X562305Y-440279D01*
X561213Y-439113D01*
X559685Y-438530D01*
X558156Y-438821D01*
X556846Y-439696D01*
X555973Y-441738D01*
X555536Y-443488D01*
Y-445238D01*
X555973Y-446988D01*
X557065Y-448738D01*
X558375Y-449904D01*
X559903Y-450196D01*
X561431Y-449613D01*
X562960Y-447863D01*
G01X576748Y-450196D02*
Y-432696D01*
G01X754448Y-495196D02*
Y-477696D01*
X751828Y-481196D01*
G01Y-495196D02*
X757068D01*
G01X767800Y-487905D02*
X769328Y-485863D01*
X770638Y-484696D01*
X772385Y-484113D01*
X773913Y-484696D01*
X775005Y-485863D01*
X775878Y-487613D01*
X776096Y-489654D01*
X775878Y-491405D01*
X775005Y-493155D01*
X773694Y-494613D01*
X772166Y-495196D01*
X770420Y-494613D01*
X768891Y-492863D01*
X768018Y-490238D01*
X767800Y-487321D01*
X768236Y-483530D01*
X768891Y-481487D01*
X769983Y-479446D01*
X771511Y-477988D01*
X773040Y-477696D01*
X774568Y-478279D01*
X775660Y-479738D01*
G01X784645Y-491696D02*
X785954Y-493738D01*
X787701Y-494904D01*
X789666Y-495196D01*
X791413Y-494904D01*
X793160Y-493446D01*
X794251Y-491696D01*
X794470Y-489946D01*
X794033Y-487905D01*
X792505Y-486446D01*
X790976Y-485863D01*
X789011D01*
G01X790976D02*
X792286Y-484988D01*
X793378Y-483530D01*
X793815Y-481780D01*
X793378Y-480029D01*
X792286Y-478571D01*
X790321Y-477696D01*
X788356Y-477988D01*
X786391Y-479155D01*
G01X806948Y-495196D02*
Y-477696D01*
X804328Y-481196D01*
G01Y-495196D02*
X809568D01*
G01X819645Y-492572D02*
X820954Y-494030D01*
X822483Y-494904D01*
X824448Y-495196D01*
X826413Y-494613D01*
X827941Y-493446D01*
X829033Y-491405D01*
X829251Y-489071D01*
X828815Y-486738D01*
X827723Y-485279D01*
X826194Y-484113D01*
X824666Y-483821D01*
X823138Y-484113D01*
X821173Y-485279D01*
X821828Y-477696D01*
X827723D01*
G01X741331Y-450196D02*
Y-432696D01*
X746571D01*
X748318Y-433571D01*
X749628Y-435613D01*
X750065Y-437946D01*
X749628Y-440279D01*
X748536Y-442029D01*
X746571Y-442905D01*
X741331D01*
G01X768001Y-434155D02*
X766691Y-433279D01*
X765163Y-432696D01*
X763416D01*
X761451Y-433571D01*
X759923Y-435029D01*
X758831Y-436780D01*
X757958Y-439696D01*
X757739Y-442321D01*
X758176Y-444946D01*
X758831Y-446696D01*
X760141Y-448446D01*
X761670Y-449613D01*
X763198Y-450196D01*
X764726D01*
X766255Y-449613D01*
X767565Y-448738D01*
X768657Y-447572D01*
G01X782444Y-440863D02*
X783318Y-439988D01*
X783973Y-438530D01*
X784410Y-436487D01*
X783973Y-434738D01*
X783100Y-433571D01*
X781571Y-432696D01*
X775676D01*
Y-450196D01*
X782881D01*
X784410Y-449030D01*
X785283Y-447279D01*
X785720Y-445238D01*
X785283Y-443196D01*
X783973Y-441446D01*
X782444Y-440863D01*
X775676D01*
G01X791648Y-456029D02*
X804748D01*
G01X810676Y-450196D02*
Y-432696D01*
X820720Y-450196D01*
Y-432696D01*
G01X833198Y-450196D02*
X831451Y-449904D01*
X829923Y-448738D01*
X828613Y-446988D01*
X827739Y-444946D01*
X827303Y-442613D01*
Y-440279D01*
X827739Y-437946D01*
X828613Y-435904D01*
X829923Y-434155D01*
X831451Y-432988D01*
X833198Y-432696D01*
X834944Y-432988D01*
X836473Y-434155D01*
X837783Y-435904D01*
X838657Y-437946D01*
X839093Y-440279D01*
Y-442613D01*
X838657Y-444946D01*
X837783Y-446988D01*
X836473Y-448738D01*
X834944Y-449904D01*
X833198Y-450196D01*
G01X884039Y-432696D02*
X889498Y-450196D01*
X894957Y-432696D01*
G01X911365Y-450196D02*
X902631D01*
Y-432696D01*
X911365D01*
G01X907871Y-441154D02*
X902631D01*
G01X920131Y-450196D02*
Y-432696D01*
X925590D01*
X927336Y-433571D01*
X928428Y-434738D01*
X928865Y-437071D01*
X928428Y-439405D01*
X927118Y-440863D01*
X925590Y-441738D01*
X920131D01*
G01X925590D02*
X928865Y-450196D01*
G01X941998Y-450779D02*
X941561Y-450488D01*
Y-449904D01*
X941998Y-449613D01*
X942435Y-449904D01*
Y-450488D01*
X941998Y-450779D01*
G01X915748Y-495196D02*
Y-477696D01*
X913128Y-481196D01*
G01Y-495196D02*
X918368D01*
G01X1082981Y-477696D02*
Y-495196D01*
X1091715D01*
G01X1107468D02*
Y-477696D01*
X1099389Y-490238D01*
X1110307D01*
G01X1123658Y-486446D02*
X1128025D01*
Y-491696D01*
X1126715Y-493446D01*
X1125186Y-494613D01*
X1123003Y-495196D01*
X1120820Y-494613D01*
X1119291Y-493446D01*
X1117981Y-491696D01*
X1117108Y-489654D01*
X1116671Y-487321D01*
Y-485279D01*
X1117108Y-483530D01*
X1117981Y-481487D01*
X1119291Y-479738D01*
X1120601Y-478571D01*
X1122348Y-477696D01*
X1123876D01*
X1125623Y-478279D01*
X1126933Y-479446D01*
G01X1134826Y-495196D02*
Y-477696D01*
X1144870Y-495196D01*
Y-477696D01*
G01X1152545Y-495196D02*
Y-477696D01*
X1156911D01*
X1158658Y-478571D01*
X1159968Y-479738D01*
X1161060Y-481487D01*
X1161933Y-483530D01*
X1162151Y-486446D01*
X1161933Y-489363D01*
X1161060Y-491405D01*
X1159968Y-493155D01*
X1158658Y-494321D01*
X1156911Y-495196D01*
X1152545D01*
G01X1082981Y-432696D02*
Y-450196D01*
X1091715D01*
G01X1108778D02*
Y-438530D01*
G01Y-440571D02*
X1107905Y-439405D01*
X1106594Y-438821D01*
X1105066Y-438530D01*
X1103538Y-439113D01*
X1102228Y-440279D01*
X1101354Y-442029D01*
X1100918Y-444363D01*
X1101354Y-446696D01*
X1102228Y-448446D01*
X1103538Y-449613D01*
X1105066Y-450196D01*
X1106594Y-449904D01*
X1107905Y-449030D01*
X1108778Y-447863D01*
G01X1117763Y-455446D02*
X1119073Y-456029D01*
X1120820Y-455446D01*
X1121911Y-454280D01*
X1122785Y-452821D01*
X1124094Y-448155D01*
X1126933Y-438530D01*
G01X1119946D02*
X1124094Y-448155D01*
G01X1136573Y-442321D02*
X1143560D01*
X1142905Y-440279D01*
X1141813Y-439113D01*
X1140285Y-438530D01*
X1138756Y-438821D01*
X1137446Y-439696D01*
X1136573Y-441738D01*
X1136136Y-443488D01*
Y-445238D01*
X1136573Y-446988D01*
X1137665Y-448738D01*
X1138975Y-449904D01*
X1140503Y-450196D01*
X1142031Y-449613D01*
X1143560Y-447863D01*
G01X1154291Y-450196D02*
Y-438530D01*
G01Y-440863D02*
X1155383Y-439696D01*
X1156475Y-438821D01*
X1158003Y-438530D01*
X1159094Y-438821D01*
X1160405Y-439696D01*
G01X1312898Y-495196D02*
X1311151Y-494904D01*
X1309623Y-493738D01*
X1308313Y-491988D01*
X1307439Y-489946D01*
X1307003Y-487613D01*
Y-485279D01*
X1307439Y-482946D01*
X1308313Y-480904D01*
X1309623Y-479155D01*
X1311151Y-477988D01*
X1312898Y-477696D01*
X1314644Y-477988D01*
X1316173Y-479155D01*
X1317483Y-480904D01*
X1318357Y-482946D01*
X1318793Y-485279D01*
Y-487613D01*
X1318357Y-489946D01*
X1317483Y-491988D01*
X1316173Y-493738D01*
X1314644Y-494904D01*
X1312898Y-495196D01*
G01X1314644Y-490529D02*
X1317265Y-495196D01*
G01X1325595Y-477696D02*
Y-490238D01*
X1326468Y-492863D01*
X1328215Y-494613D01*
X1330398Y-495196D01*
X1332581Y-494613D01*
X1334328Y-492863D01*
X1335201Y-490238D01*
Y-477696D01*
G01X1345278D02*
X1350518D01*
G01X1347898D02*
Y-495196D01*
G01X1345278D02*
X1350518D01*
G01X1360376D02*
Y-477696D01*
X1370420Y-495196D01*
Y-477696D01*
G01X1387701Y-479155D02*
X1386391Y-478279D01*
X1384863Y-477696D01*
X1383116D01*
X1381151Y-478571D01*
X1379623Y-480029D01*
X1378531Y-481780D01*
X1377658Y-484696D01*
X1377439Y-487321D01*
X1377876Y-489946D01*
X1378531Y-491696D01*
X1379841Y-493446D01*
X1381370Y-494613D01*
X1382898Y-495196D01*
X1384426D01*
X1385955Y-494613D01*
X1387265Y-493738D01*
X1388357Y-492572D01*
G01X1400398Y-495196D02*
Y-487321D01*
X1396031Y-477696D01*
G01X1404765D02*
X1400398Y-487321D01*
G01X1290595Y-450196D02*
Y-432696D01*
X1294961D01*
X1296708Y-433571D01*
X1298018Y-434738D01*
X1299110Y-436487D01*
X1299983Y-438530D01*
X1300201Y-441446D01*
X1299983Y-444363D01*
X1299110Y-446405D01*
X1298018Y-448155D01*
X1296708Y-449321D01*
X1294961Y-450196D01*
X1290595D01*
G01X1309623Y-442321D02*
X1316610D01*
X1315955Y-440279D01*
X1314863Y-439113D01*
X1313335Y-438530D01*
X1311806Y-438821D01*
X1310496Y-439696D01*
X1309623Y-441738D01*
X1309186Y-443488D01*
Y-445238D01*
X1309623Y-446988D01*
X1310715Y-448738D01*
X1312025Y-449904D01*
X1313553Y-450196D01*
X1315081Y-449613D01*
X1316610Y-447863D01*
G01X1327123Y-448155D02*
X1328215Y-449321D01*
X1329743Y-450196D01*
X1331053D01*
X1332363Y-449613D01*
X1333236Y-448738D01*
X1333673Y-447572D01*
X1333455Y-445821D01*
X1332581Y-444946D01*
X1328651Y-443196D01*
X1327778Y-441154D01*
X1328215Y-439696D01*
X1329088Y-438821D01*
X1330398Y-438530D01*
X1331708Y-438821D01*
X1333018Y-439696D01*
G01X1347898Y-438530D02*
Y-450196D01*
G01Y-433863D02*
X1347461Y-433571D01*
Y-432988D01*
X1347898Y-432696D01*
X1348335Y-432988D01*
Y-433571D01*
X1347898Y-433863D01*
G01X1362341Y-454571D02*
X1363870Y-455738D01*
X1365616Y-456029D01*
X1367144Y-455738D01*
X1368455Y-454280D01*
X1369328Y-452238D01*
Y-438530D01*
G01Y-440863D02*
X1368455Y-439696D01*
X1367144Y-438821D01*
X1365616Y-438530D01*
X1363870Y-439113D01*
X1362778Y-440279D01*
X1361904Y-442321D01*
X1361468Y-444363D01*
X1361686Y-446113D01*
X1362560Y-448155D01*
X1363870Y-449613D01*
X1365616Y-450196D01*
X1366926Y-449904D01*
X1368455Y-448738D01*
X1369328Y-447572D01*
G01X1379186Y-450196D02*
Y-438530D01*
G01Y-441446D02*
X1380060Y-439988D01*
X1381370Y-438821D01*
X1383116Y-438530D01*
X1384644Y-438821D01*
X1385955Y-439988D01*
X1386610Y-442029D01*
Y-450196D01*
G01X1397123Y-442321D02*
X1404110D01*
X1403455Y-440279D01*
X1402363Y-439113D01*
X1400835Y-438530D01*
X1399306Y-438821D01*
X1397996Y-439696D01*
X1397123Y-441738D01*
X1396686Y-443488D01*
Y-445238D01*
X1397123Y-446988D01*
X1398215Y-448738D01*
X1399525Y-449904D01*
X1401053Y-450196D01*
X1402581Y-449613D01*
X1404110Y-447863D01*
G01X1414841Y-450196D02*
Y-438530D01*
G01Y-440863D02*
X1415933Y-439696D01*
X1417025Y-438821D01*
X1418553Y-438530D01*
X1419644Y-438821D01*
X1420955Y-439696D01*
G01X1461598Y-477696D02*
X1459851Y-478279D01*
X1458541Y-479738D01*
X1457668Y-481487D01*
X1457013Y-483821D01*
X1456795Y-486446D01*
X1457013Y-489071D01*
X1457668Y-491405D01*
X1458541Y-493155D01*
X1459851Y-494613D01*
X1461598Y-495196D01*
X1463344Y-494613D01*
X1464655Y-493155D01*
X1465528Y-491405D01*
X1466183Y-489071D01*
X1466401Y-486446D01*
X1466183Y-483821D01*
X1465528Y-481487D01*
X1464655Y-479738D01*
X1463344Y-478279D01*
X1461598Y-477696D01*
G01X1474950Y-487905D02*
X1476478Y-485863D01*
X1477788Y-484696D01*
X1479535Y-484113D01*
X1481063Y-484696D01*
X1482155Y-485863D01*
X1483028Y-487613D01*
X1483246Y-489654D01*
X1483028Y-491405D01*
X1482155Y-493155D01*
X1480844Y-494613D01*
X1479316Y-495196D01*
X1477570Y-494613D01*
X1476041Y-492863D01*
X1475168Y-490238D01*
X1474950Y-487321D01*
X1475386Y-483530D01*
X1476041Y-481487D01*
X1477133Y-479446D01*
X1478661Y-477988D01*
X1480190Y-477696D01*
X1481718Y-478279D01*
X1482810Y-479738D01*
G01X1492668Y-495779D02*
X1500528Y-477696D01*
G01X1514098D02*
X1512351Y-478279D01*
X1511041Y-479738D01*
X1510168Y-481487D01*
X1509513Y-483821D01*
X1509295Y-486446D01*
X1509513Y-489071D01*
X1510168Y-491405D01*
X1511041Y-493155D01*
X1512351Y-494613D01*
X1514098Y-495196D01*
X1515844Y-494613D01*
X1517155Y-493155D01*
X1518028Y-491405D01*
X1518683Y-489071D01*
X1518901Y-486446D01*
X1518683Y-483821D01*
X1518028Y-481487D01*
X1517155Y-479738D01*
X1515844Y-478279D01*
X1514098Y-477696D01*
G01X1527886Y-493155D02*
X1529415Y-494613D01*
X1531161Y-495196D01*
X1532908Y-494613D01*
X1534436Y-492863D01*
X1535528Y-490238D01*
X1535965Y-487613D01*
Y-484405D01*
X1535528Y-481780D01*
X1534436Y-479446D01*
X1533126Y-478279D01*
X1531598Y-477696D01*
X1529851Y-478279D01*
X1528541Y-479446D01*
X1527668Y-481196D01*
X1527231Y-483530D01*
X1527668Y-485571D01*
X1528760Y-487613D01*
X1530070Y-488780D01*
X1531598Y-489071D01*
X1533344Y-488488D01*
X1534655Y-487029D01*
X1535965Y-484405D01*
G01X1545168Y-495779D02*
X1553028Y-477696D01*
G01X1562450Y-480613D02*
X1563760Y-478863D01*
X1565288Y-477988D01*
X1567035Y-477696D01*
X1569218Y-478279D01*
X1570746Y-479738D01*
X1571183Y-481487D01*
X1570965Y-483238D01*
X1570091Y-484696D01*
X1565725Y-487613D01*
X1563760Y-489654D01*
X1562450Y-492572D01*
X1562013Y-495196D01*
X1571183D01*
G01X1584098Y-477696D02*
X1582351Y-478279D01*
X1581041Y-479738D01*
X1580168Y-481487D01*
X1579513Y-483821D01*
X1579295Y-486446D01*
X1579513Y-489071D01*
X1580168Y-491405D01*
X1581041Y-493155D01*
X1582351Y-494613D01*
X1584098Y-495196D01*
X1585844Y-494613D01*
X1587155Y-493155D01*
X1588028Y-491405D01*
X1588683Y-489071D01*
X1588901Y-486446D01*
X1588683Y-483821D01*
X1588028Y-481487D01*
X1587155Y-479738D01*
X1585844Y-478279D01*
X1584098Y-477696D01*
G01X1601598Y-495196D02*
Y-477696D01*
X1598978Y-481196D01*
G01Y-495196D02*
X1604218D01*
G01X1618661D02*
X1619098Y-491405D01*
X1619753Y-488196D01*
X1620626Y-485279D01*
X1621718Y-482071D01*
X1623465Y-477696D01*
X1614731D01*
G01X1509295Y-450196D02*
Y-432696D01*
X1513661D01*
X1515408Y-433571D01*
X1516718Y-434738D01*
X1517810Y-436487D01*
X1518683Y-438530D01*
X1518901Y-441446D01*
X1518683Y-444363D01*
X1517810Y-446405D01*
X1516718Y-448155D01*
X1515408Y-449321D01*
X1513661Y-450196D01*
X1509295D01*
G01X1535528D02*
Y-438530D01*
G01Y-440571D02*
X1534655Y-439405D01*
X1533344Y-438821D01*
X1531816Y-438530D01*
X1530288Y-439113D01*
X1528978Y-440279D01*
X1528104Y-442029D01*
X1527668Y-444363D01*
X1528104Y-446696D01*
X1528978Y-448446D01*
X1530288Y-449613D01*
X1531816Y-450196D01*
X1533344Y-449904D01*
X1534655Y-449030D01*
X1535528Y-447863D01*
G01X1549098Y-432696D02*
Y-450196D01*
G01X1546041Y-438530D02*
X1552155D01*
G01X1563323Y-442321D02*
X1570310D01*
X1569655Y-440279D01*
X1568563Y-439113D01*
X1567035Y-438530D01*
X1565506Y-438821D01*
X1564196Y-439696D01*
X1563323Y-441738D01*
X1562886Y-443488D01*
Y-445238D01*
X1563323Y-446988D01*
X1564415Y-448738D01*
X1565725Y-449904D01*
X1567253Y-450196D01*
X1568781Y-449613D01*
X1570310Y-447863D01*
M02*
